G04 ================== begin FILE IDENTIFICATION RECORD ==================*
G04 Layout Name:  16368-sb.brd*
G04 Film Name:    BSMD*
G04 File Format:  Gerber RS274X*
G04 File Origin:  Cadence Allegro 16.5-S056*
G04 Origin Date:  Tue Feb 07 09:07:39 2017*
G04 *
G04 Layer:  VIA CLASS/PASTEMASK_BOTTOM*
G04 Layer:  PIN/PASTEMASK_BOTTOM*
G04 Layer:  PACKAGE GEOMETRY/PASTEMASK_BOTTOM*
G04 Layer:  DRAWING FORMAT/LAYER_PCB_STORY*
G04 Layer:  DRAWING FORMAT/LAYER_PAST_B*
G04 Layer:  BOARD GEOMETRY/PANEL_OUTLINE*
G04 *
G04 Offset:    (0.00 0.00)*
G04 Mirror:    No*
G04 Mode:      Positive*
G04 Rotation:  0*
G04 FullContactRelief:  No*
G04 UndefLineWidth:     6.00*
G04 ================== end FILE IDENTIFICATION RECORD ====================*
%FSLAX35Y35*MOIN*%
%IR0*IPPOS*OFA0.00000B0.00000*MIA0B0*SFA1.00000B1.00000*%
%AMMACRO16*
4,1,40,.011,.007,
.011,-.007,
.010939,-.007695,
.010759,-.008368,
.010464,-.009,
.010064,-.009571,
.009571,-.010064,
.009,-.010464,
.008368,-.010759,
.007695,-.010939,
.007,-.011,
-.007,-.011,
-.007695,-.010939,
-.008368,-.010759,
-.009,-.010464,
-.009571,-.010064,
-.010064,-.009571,
-.010464,-.009,
-.010759,-.008368,
-.010939,-.007695,
-.011,-.007,
-.011,.007,
-.010939,.007695,
-.010759,.008368,
-.010464,.009,
-.010064,.009571,
-.009571,.010064,
-.009,.010464,
-.008368,.010759,
-.007695,.010939,
-.007,.011,
.007,.011,
.007695,.010939,
.008368,.010759,
.009,.010464,
.009571,.010064,
.010064,.009571,
.010464,.009,
.010759,.008368,
.010939,.007695,
.011,.007,
0.0*
%
%ADD16MACRO16*%
%ADD10C,.04*%
%ADD23C,.024*%
%ADD12R,.039X.108*%
%ADD11C,.086*%
%AMMACRO24*
4,1,40,-.011,-.007,
-.011,.007,
-.010939,.007695,
-.010759,.008368,
-.010464,.009,
-.010064,.009571,
-.009571,.010064,
-.009,.010464,
-.008368,.010759,
-.007695,.010939,
-.007,.011,
.007,.011,
.007695,.010939,
.008368,.010759,
.009,.010464,
.009571,.010064,
.010064,.009571,
.010464,.009,
.010759,.008368,
.010939,.007695,
.011,.007,
.011,-.007,
.010939,-.007695,
.010759,-.008368,
.010464,-.009,
.010064,-.009571,
.009571,-.010064,
.009,-.010464,
.008368,-.010759,
.007695,-.010939,
.007,-.011,
-.007,-.011,
-.007695,-.010939,
-.008368,-.010759,
-.009,-.010464,
-.009571,-.010064,
-.010064,-.009571,
-.010464,-.009,
-.010759,-.008368,
-.010939,-.007695,
-.011,-.007,
0.0*
%
%ADD24MACRO24*%
%AMMACRO13*
4,1,40,.007,-.011,
-.007,-.011,
-.007695,-.010939,
-.008368,-.010759,
-.009,-.010464,
-.009571,-.010064,
-.010064,-.009571,
-.010464,-.009,
-.010759,-.008368,
-.010939,-.007695,
-.011,-.007,
-.011,.007,
-.010939,.007695,
-.010759,.008368,
-.010464,.009,
-.010064,.009571,
-.009571,.010064,
-.009,.010464,
-.008368,.010759,
-.007695,.010939,
-.007,.011,
.007,.011,
.007695,.010939,
.008368,.010759,
.009,.010464,
.009571,.010064,
.010064,.009571,
.010464,.009,
.010759,.008368,
.010939,.007695,
.011,.007,
.011,-.007,
.010939,-.007695,
.010759,-.008368,
.010464,-.009,
.010064,-.009571,
.009571,-.010064,
.009,-.010464,
.008368,-.010759,
.007695,-.010939,
.007,-.011,
0.0*
%
%ADD13MACRO13*%
%AMMACRO20*
4,1,44,.023,.00387,
.022901,.005261,
.022562,.006614,
.021993,.007887,
.021211,.009042,
.020241,.010044,
.019112,.010863,
.017857,.011472,
.016516,.011855,
.015129,.011999,
.015,.012,
-.015,.012,
-.016389,.011878,
-.017737,.011517,
-.019001,.010928,
-.020143,.010128,
-.021129,.009142,
-.021929,.007999,
-.022519,.006735,
-.022879,.005388,
-.023001,.003999,
-.023,.00387,
-.023,-.00387,
-.022901,-.005261,
-.022562,-.006614,
-.021993,-.007887,
-.021211,-.009042,
-.020241,-.010044,
-.019112,-.010863,
-.017857,-.011472,
-.016516,-.011855,
-.015129,-.011999,
-.015,-.012,
.015,-.012,
.016389,-.011878,
.017737,-.011517,
.019001,-.010928,
.020143,-.010128,
.021129,-.009142,
.021929,-.007999,
.022519,-.006735,
.022879,-.005388,
.023001,-.003999,
.023,-.00387,
.023,.00387,
0.0*
%
%ADD20MACRO20*%
%AMMACRO21*
4,1,40,-.013,.017,
.013,.017,
.013695,.016939,
.014368,.016759,
.015,.016464,
.015571,.016064,
.016064,.015571,
.016464,.015,
.016759,.014368,
.016939,.013695,
.017,.013,
.017,-.013,
.016939,-.013695,
.016759,-.014368,
.016464,-.015,
.016064,-.015571,
.015571,-.016064,
.015,-.016464,
.014368,-.016759,
.013695,-.016939,
.013,-.017,
-.013,-.017,
-.013695,-.016939,
-.014368,-.016759,
-.015,-.016464,
-.015571,-.016064,
-.016064,-.015571,
-.016464,-.015,
-.016759,-.014368,
-.016939,-.013695,
-.017,-.013,
-.017,.013,
-.016939,.013695,
-.016759,.014368,
-.016464,.015,
-.016064,.015571,
-.015571,.016064,
-.015,.016464,
-.014368,.016759,
-.013695,.016939,
-.013,.017,
0.0*
%
%ADD21MACRO21*%
%AMMACRO25*
4,1,40,-.011,-.007,
-.011,.007,
-.010939,.007695,
-.010759,.008368,
-.010464,.009,
-.010064,.009571,
-.009571,.010064,
-.009,.010464,
-.008368,.010759,
-.007695,.010939,
-.007,.011,
.007,.011,
.007695,.010939,
.008368,.010759,
.009,.010464,
.009571,.010064,
.010064,.009571,
.010464,.009,
.010759,.008368,
.010939,.007695,
.011,.007,
.011,-.007,
.010939,-.007695,
.010759,-.008368,
.010464,-.009,
.010064,-.009571,
.009571,-.010064,
.009,-.010464,
.008368,-.010759,
.007695,-.010939,
.007,-.011,
-.007,-.011,
-.007695,-.010939,
-.008368,-.010759,
-.009,-.010464,
-.009571,-.010064,
-.010064,-.009571,
-.010464,-.009,
-.010759,-.008368,
-.010939,-.007695,
-.011,-.007,
0.0*
%
%ADD25MACRO25*%
%AMMACRO14*
4,1,40,.007,-.011,
-.007,-.011,
-.007695,-.010939,
-.008368,-.010759,
-.009,-.010464,
-.009571,-.010064,
-.010064,-.009571,
-.010464,-.009,
-.010759,-.008368,
-.010939,-.007695,
-.011,-.007,
-.011,.007,
-.010939,.007695,
-.010759,.008368,
-.010464,.009,
-.010064,.009571,
-.009571,.010064,
-.009,.010464,
-.008368,.010759,
-.007695,.010939,
-.007,.011,
.007,.011,
.007695,.010939,
.008368,.010759,
.009,.010464,
.009571,.010064,
.010064,.009571,
.010464,.009,
.010759,.008368,
.010939,.007695,
.011,.007,
.011,-.007,
.010939,-.007695,
.010759,-.008368,
.010464,-.009,
.010064,-.009571,
.009571,-.010064,
.009,-.010464,
.008368,-.010759,
.007695,-.010939,
.007,-.011,
0.0*
%
%ADD14MACRO14*%
%AMMACRO22*
4,1,40,-.013,.017,
.013,.017,
.013695,.016939,
.014368,.016759,
.015,.016464,
.015571,.016064,
.016064,.015571,
.016464,.015,
.016759,.014368,
.016939,.013695,
.017,.013,
.017,-.013,
.016939,-.013695,
.016759,-.014368,
.016464,-.015,
.016064,-.015571,
.015571,-.016064,
.015,-.016464,
.014368,-.016759,
.013695,-.016939,
.013,-.017,
-.013,-.017,
-.013695,-.016939,
-.014368,-.016759,
-.015,-.016464,
-.015571,-.016064,
-.016064,-.015571,
-.016464,-.015,
-.016759,-.014368,
-.016939,-.013695,
-.017,-.013,
-.017,.013,
-.016939,.013695,
-.016759,.014368,
-.016464,.015,
-.016064,.015571,
-.015571,.016064,
-.015,.016464,
-.014368,.016759,
-.013695,.016939,
-.013,.017,
0.0*
%
%ADD22MACRO22*%
%ADD28R,.04X.022*%
%ADD17R,.032X.071*%
%ADD18R,.024X.063*%
%ADD19R,.016X.048*%
%AMMACRO27*
4,1,40,.008,-.012,
-.008,-.012,
-.008695,-.011939,
-.009368,-.011759,
-.01,-.011464,
-.010571,-.011064,
-.011064,-.010571,
-.011464,-.01,
-.011759,-.009368,
-.011939,-.008695,
-.012,-.008,
-.012,.008,
-.011939,.008695,
-.011759,.009368,
-.011464,.01,
-.011064,.010571,
-.010571,.011064,
-.01,.011464,
-.009368,.011759,
-.008695,.011939,
-.008,.012,
.008,.012,
.008695,.011939,
.009368,.011759,
.01,.011464,
.010571,.011064,
.011064,.010571,
.011464,.01,
.011759,.009368,
.011939,.008695,
.012,.008,
.012,-.008,
.011939,-.008695,
.011759,-.009368,
.011464,-.01,
.011064,-.010571,
.010571,-.011064,
.01,-.011464,
.009368,-.011759,
.008695,-.011939,
.008,-.012,
0.0*
%
%ADD27MACRO27*%
%AMMACRO15*
4,1,40,.011,.007,
.011,-.007,
.010939,-.007695,
.010759,-.008368,
.010464,-.009,
.010064,-.009571,
.009571,-.010064,
.009,-.010464,
.008368,-.010759,
.007695,-.010939,
.007,-.011,
-.007,-.011,
-.007695,-.010939,
-.008368,-.010759,
-.009,-.010464,
-.009571,-.010064,
-.010064,-.009571,
-.010464,-.009,
-.010759,-.008368,
-.010939,-.007695,
-.011,-.007,
-.011,.007,
-.010939,.007695,
-.010759,.008368,
-.010464,.009,
-.010064,.009571,
-.009571,.010064,
-.009,.010464,
-.008368,.010759,
-.007695,.010939,
-.007,.011,
.007,.011,
.007695,.010939,
.008368,.010759,
.009,.010464,
.009571,.010064,
.010064,.009571,
.010464,.009,
.010759,.008368,
.010939,.007695,
.011,.007,
0.0*
%
%ADD15MACRO15*%
%AMMACRO26*
4,1,40,.008,-.012,
-.008,-.012,
-.008695,-.011939,
-.009368,-.011759,
-.01,-.011464,
-.010571,-.011064,
-.011064,-.010571,
-.011464,-.01,
-.011759,-.009368,
-.011939,-.008695,
-.012,-.008,
-.012,.008,
-.011939,.008695,
-.011759,.009368,
-.011464,.01,
-.011064,.010571,
-.010571,.011064,
-.01,.011464,
-.009368,.011759,
-.008695,.011939,
-.008,.012,
.008,.012,
.008695,.011939,
.009368,.011759,
.01,.011464,
.010571,.011064,
.011064,.010571,
.011464,.01,
.011759,.009368,
.011939,.008695,
.012,.008,
.012,-.008,
.011939,-.008695,
.011759,-.009368,
.011464,-.01,
.011064,-.010571,
.010571,-.011064,
.01,-.011464,
.009368,-.011759,
.008695,-.011939,
.008,-.012,
0.0*
%
%ADD26MACRO26*%
%ADD29C,.02*%
%ADD30C,.006*%
G75*
%LPD*%
G75*
G54D10*
X25827Y-9492D03*
X148500Y47500D03*
X519227Y-9492D03*
G54D20*
X113950Y11000D03*
X121050Y13560D03*
Y8440D03*
G54D11*
X9000Y48000D03*
X164500Y48500D03*
G54D30*
G01X-137600Y-128617D02*
Y-146117D01*
X-128866D01*
G01X-113987Y-136784D02*
X-113113Y-135909D01*
X-112458Y-134451D01*
X-112021Y-132408D01*
X-112458Y-130659D01*
X-113331Y-129492D01*
X-114860Y-128617D01*
X-120755D01*
Y-146117D01*
X-113550D01*
X-112021Y-144951D01*
X-111148Y-143200D01*
X-110711Y-141159D01*
X-111148Y-139117D01*
X-112458Y-137367D01*
X-113987Y-136784D01*
X-120755D01*
G01X-93430Y-130076D02*
X-94740Y-129200D01*
X-96268Y-128617D01*
X-98015D01*
X-99980Y-129492D01*
X-101508Y-130950D01*
X-102600Y-132701D01*
X-103473Y-135617D01*
X-103692Y-138242D01*
X-103255Y-140867D01*
X-102600Y-142617D01*
X-101290Y-144367D01*
X-99761Y-145534D01*
X-98233Y-146117D01*
X-96705D01*
X-95176Y-145534D01*
X-93866Y-144659D01*
X-92774Y-143493D01*
G01X-67600Y-128617D02*
Y-146117D01*
X-58866D01*
G01X-41366D02*
X-50100D01*
Y-128617D01*
X-41366D01*
G01X-44860Y-137075D02*
X-50100D01*
G01X-33036Y-146117D02*
Y-128617D01*
X-28670D01*
X-26923Y-129492D01*
X-25613Y-130659D01*
X-24521Y-132408D01*
X-23648Y-134451D01*
X-23430Y-137367D01*
X-23648Y-140284D01*
X-24521Y-142326D01*
X-25613Y-144076D01*
X-26923Y-145242D01*
X-28670Y-146117D01*
X-33036D01*
G01X10260Y-135909D02*
X8732Y-134742D01*
X7422Y-134451D01*
X5675Y-135034D01*
X4365Y-136200D01*
X3492Y-138242D01*
X3273Y-140284D01*
X3492Y-142326D01*
X4365Y-144076D01*
X5675Y-145534D01*
X7422Y-146117D01*
X8950Y-145534D01*
X10260Y-144367D01*
G01X28197Y-146117D02*
Y-134451D01*
G01Y-136492D02*
X27324Y-135326D01*
X26013Y-134742D01*
X24485Y-134451D01*
X22957Y-135034D01*
X21647Y-136200D01*
X20773Y-137950D01*
X20337Y-140284D01*
X20773Y-142617D01*
X21647Y-144367D01*
X22957Y-145534D01*
X24485Y-146117D01*
X26013Y-145825D01*
X27324Y-144951D01*
X28197Y-143784D01*
G01X38710Y-146117D02*
Y-134451D01*
G01Y-136784D02*
X39802Y-135617D01*
X40894Y-134742D01*
X42422Y-134451D01*
X43513Y-134742D01*
X44824Y-135617D01*
G01X63197Y-128617D02*
Y-146117D01*
G01Y-143493D02*
X62324Y-144951D01*
X61013Y-145825D01*
X59485Y-146117D01*
X57739Y-145534D01*
X56429Y-144076D01*
X55555Y-142326D01*
X55337Y-140284D01*
X55555Y-138242D01*
X56429Y-136492D01*
X57739Y-135034D01*
X59485Y-134451D01*
X61013Y-134742D01*
X62105Y-135326D01*
X63197Y-136492D01*
G01X-77660Y-101117D02*
Y-83617D01*
X-71983Y-98200D01*
X-66306Y-83617D01*
Y-101117D01*
G01X-54483D02*
X-55793Y-100825D01*
X-57103Y-99659D01*
X-57977Y-97617D01*
X-58413Y-95284D01*
X-57977Y-92950D01*
X-57103Y-90909D01*
X-55793Y-89742D01*
X-54483Y-89451D01*
X-53173Y-89742D01*
X-51863Y-90909D01*
X-50990Y-92950D01*
X-50771Y-95284D01*
X-50990Y-97617D01*
X-51863Y-99659D01*
X-53173Y-100825D01*
X-54483Y-101117D01*
G01X-33053Y-83617D02*
Y-101117D01*
G01Y-98493D02*
X-33926Y-99951D01*
X-35237Y-100825D01*
X-36765Y-101117D01*
X-38511Y-100534D01*
X-39821Y-99076D01*
X-40695Y-97326D01*
X-40913Y-95284D01*
X-40695Y-93242D01*
X-39821Y-91492D01*
X-38511Y-90034D01*
X-36765Y-89451D01*
X-35237Y-89742D01*
X-34145Y-90326D01*
X-33053Y-91492D01*
G01X-22758Y-93242D02*
X-15771D01*
X-16426Y-91200D01*
X-17518Y-90034D01*
X-19046Y-89451D01*
X-20575Y-89742D01*
X-21885Y-90617D01*
X-22758Y-92659D01*
X-23195Y-94409D01*
Y-96159D01*
X-22758Y-97909D01*
X-21666Y-99659D01*
X-20356Y-100825D01*
X-18828Y-101117D01*
X-17300Y-100534D01*
X-15771Y-98784D01*
G01X-1983Y-101117D02*
Y-83617D01*
G01X110317Y-146117D02*
Y-128617D01*
X107697Y-132117D01*
G01Y-146117D02*
X112937D01*
G01X123669Y-138826D02*
X125197Y-136784D01*
X126507Y-135617D01*
X128254Y-135034D01*
X129782Y-135617D01*
X130874Y-136784D01*
X131747Y-138534D01*
X131965Y-140575D01*
X131747Y-142326D01*
X130874Y-144076D01*
X129563Y-145534D01*
X128035Y-146117D01*
X126289Y-145534D01*
X124760Y-143784D01*
X123887Y-141159D01*
X123669Y-138242D01*
X124105Y-134451D01*
X124760Y-132408D01*
X125852Y-130367D01*
X127380Y-128909D01*
X128909Y-128617D01*
X130437Y-129200D01*
X131529Y-130659D01*
G01X140514Y-142617D02*
X141823Y-144659D01*
X143570Y-145825D01*
X145535Y-146117D01*
X147282Y-145825D01*
X149029Y-144367D01*
X150120Y-142617D01*
X150339Y-140867D01*
X149902Y-138826D01*
X148374Y-137367D01*
X146845Y-136784D01*
X144880D01*
G01X146845D02*
X148155Y-135909D01*
X149247Y-134451D01*
X149684Y-132701D01*
X149247Y-130950D01*
X148155Y-129492D01*
X146190Y-128617D01*
X144225Y-128909D01*
X142260Y-130076D01*
G01X158669Y-138826D02*
X160197Y-136784D01*
X161507Y-135617D01*
X163254Y-135034D01*
X164782Y-135617D01*
X165874Y-136784D01*
X166747Y-138534D01*
X166965Y-140575D01*
X166747Y-142326D01*
X165874Y-144076D01*
X164563Y-145534D01*
X163035Y-146117D01*
X161289Y-145534D01*
X159760Y-143784D01*
X158887Y-141159D01*
X158669Y-138242D01*
X159105Y-134451D01*
X159760Y-132408D01*
X160852Y-130367D01*
X162380Y-128909D01*
X163909Y-128617D01*
X165437Y-129200D01*
X166529Y-130659D01*
G01X180317Y-146117D02*
X181845Y-145825D01*
X183592Y-144951D01*
X184684Y-143493D01*
X185120Y-141450D01*
X184684Y-139409D01*
X183374Y-137659D01*
X181409Y-136784D01*
X179225D01*
X177915Y-136200D01*
X176823Y-134742D01*
X176387Y-132701D01*
X177042Y-130659D01*
X178570Y-129200D01*
X180317Y-128617D01*
X182063Y-129200D01*
X183592Y-130659D01*
X184247Y-132701D01*
X183810Y-134742D01*
X182719Y-136200D01*
X181409Y-136784D01*
X179225D01*
X177260Y-137659D01*
X175950Y-139409D01*
X175514Y-141450D01*
X175950Y-143493D01*
X177042Y-144951D01*
X178789Y-145825D01*
X180317Y-146117D01*
G01X97200Y-101117D02*
Y-83617D01*
X102440D01*
X104187Y-84492D01*
X105497Y-86534D01*
X105934Y-88867D01*
X105497Y-91200D01*
X104405Y-92950D01*
X102440Y-93826D01*
X97200D01*
G01X123870Y-85076D02*
X122560Y-84200D01*
X121032Y-83617D01*
X119285D01*
X117320Y-84492D01*
X115792Y-85950D01*
X114700Y-87701D01*
X113827Y-90617D01*
X113608Y-93242D01*
X114045Y-95867D01*
X114700Y-97617D01*
X116010Y-99367D01*
X117539Y-100534D01*
X119067Y-101117D01*
X120595D01*
X122124Y-100534D01*
X123434Y-99659D01*
X124526Y-98493D01*
G01X138313Y-91784D02*
X139187Y-90909D01*
X139842Y-89451D01*
X140279Y-87408D01*
X139842Y-85659D01*
X138969Y-84492D01*
X137440Y-83617D01*
X131545D01*
Y-101117D01*
X138750D01*
X140279Y-99951D01*
X141152Y-98200D01*
X141589Y-96159D01*
X141152Y-94117D01*
X139842Y-92367D01*
X138313Y-91784D01*
X131545D01*
G01X147517Y-106950D02*
X160617D01*
G01X166545Y-101117D02*
Y-83617D01*
X176589Y-101117D01*
Y-83617D01*
G01X189067Y-101117D02*
X187320Y-100825D01*
X185792Y-99659D01*
X184482Y-97909D01*
X183608Y-95867D01*
X183172Y-93534D01*
Y-91200D01*
X183608Y-88867D01*
X184482Y-86825D01*
X185792Y-85076D01*
X187320Y-83909D01*
X189067Y-83617D01*
X190813Y-83909D01*
X192342Y-85076D01*
X193652Y-86825D01*
X194526Y-88867D01*
X194962Y-91200D01*
Y-93534D01*
X194526Y-95867D01*
X193652Y-97909D01*
X192342Y-99659D01*
X190813Y-100825D01*
X189067Y-101117D01*
G01X258282Y-143784D02*
X260029Y-145242D01*
X261994Y-146117D01*
X263740D01*
X265487Y-145242D01*
X266797Y-143784D01*
X267452Y-141742D01*
X267015Y-139701D01*
X265924Y-137950D01*
X263959Y-136784D01*
X261339Y-136200D01*
X259810Y-135034D01*
X259155Y-132992D01*
X259592Y-130950D01*
X260684Y-129492D01*
X262212Y-128617D01*
X263740D01*
X265269Y-129200D01*
X266579Y-130659D01*
G01X282113Y-136784D02*
X282987Y-135909D01*
X283642Y-134451D01*
X284079Y-132408D01*
X283642Y-130659D01*
X282769Y-129492D01*
X281240Y-128617D01*
X275345D01*
Y-146117D01*
X282550D01*
X284079Y-144951D01*
X284952Y-143200D01*
X285389Y-141159D01*
X284952Y-139117D01*
X283642Y-137367D01*
X282113Y-136784D01*
X275345D01*
G01X239908Y-83617D02*
X245367Y-101117D01*
X250826Y-83617D01*
G01X267234Y-101117D02*
X258500D01*
Y-83617D01*
X267234D01*
G01X263740Y-92075D02*
X258500D01*
G01X276000Y-101117D02*
Y-83617D01*
X281459D01*
X283205Y-84492D01*
X284297Y-85659D01*
X284734Y-87992D01*
X284297Y-90326D01*
X282987Y-91784D01*
X281459Y-92659D01*
X276000D01*
G01X281459D02*
X284734Y-101117D01*
G01X297867Y-101700D02*
X297430Y-101409D01*
Y-100825D01*
X297867Y-100534D01*
X298304Y-100825D01*
Y-101409D01*
X297867Y-101700D01*
G01X437321Y-136784D02*
X436447Y-135909D01*
X435792Y-134451D01*
X435355Y-132408D01*
X435792Y-130659D01*
X436665Y-129492D01*
X438194Y-128617D01*
X444089D01*
Y-146117D01*
X436884D01*
X435355Y-144951D01*
X434482Y-143200D01*
X434045Y-141159D01*
X434482Y-139117D01*
X435792Y-137367D01*
X437321Y-136784D01*
X444089D01*
G01X426152Y-143784D02*
X424405Y-145242D01*
X422440Y-146117D01*
X420694D01*
X418947Y-145242D01*
X417637Y-143784D01*
X416982Y-141742D01*
X417419Y-139701D01*
X418510Y-137950D01*
X420475Y-136784D01*
X423095Y-136200D01*
X424624Y-135034D01*
X425279Y-132992D01*
X424842Y-130950D01*
X423750Y-129492D01*
X422222Y-128617D01*
X420694D01*
X419165Y-129200D01*
X417855Y-130659D01*
G01X409744Y-146117D02*
Y-128617D01*
X404067Y-143200D01*
X398390Y-128617D01*
Y-146117D01*
G01X391370D02*
Y-128617D01*
X387004D01*
X385257Y-129492D01*
X383947Y-130659D01*
X382855Y-132408D01*
X381982Y-134451D01*
X381764Y-137367D01*
X381982Y-140284D01*
X382855Y-142326D01*
X383947Y-144076D01*
X385257Y-145242D01*
X387004Y-146117D01*
X391370D01*
G01X373450Y-83617D02*
Y-101117D01*
X382184D01*
G01X399247D02*
Y-89451D01*
G01Y-91492D02*
X398374Y-90326D01*
X397063Y-89742D01*
X395535Y-89451D01*
X394007Y-90034D01*
X392697Y-91200D01*
X391823Y-92950D01*
X391387Y-95284D01*
X391823Y-97617D01*
X392697Y-99367D01*
X394007Y-100534D01*
X395535Y-101117D01*
X397063Y-100825D01*
X398374Y-99951D01*
X399247Y-98784D01*
G01X408232Y-106367D02*
X409542Y-106950D01*
X411289Y-106367D01*
X412380Y-105201D01*
X413254Y-103742D01*
X414563Y-99076D01*
X417402Y-89451D01*
G01X410415D02*
X414563Y-99076D01*
G01X427042Y-93242D02*
X434029D01*
X433374Y-91200D01*
X432282Y-90034D01*
X430754Y-89451D01*
X429225Y-89742D01*
X427915Y-90617D01*
X427042Y-92659D01*
X426605Y-94409D01*
Y-96159D01*
X427042Y-97909D01*
X428134Y-99659D01*
X429444Y-100825D01*
X430972Y-101117D01*
X432500Y-100534D01*
X434029Y-98784D01*
G01X444760Y-101117D02*
Y-89451D01*
G01Y-91784D02*
X445852Y-90617D01*
X446944Y-89742D01*
X448472Y-89451D01*
X449563Y-89742D01*
X450874Y-90617D01*
G01X515564Y-101117D02*
Y-83617D01*
X519930D01*
X521677Y-84492D01*
X522987Y-85659D01*
X524079Y-87408D01*
X524952Y-89451D01*
X525170Y-92367D01*
X524952Y-95284D01*
X524079Y-97326D01*
X522987Y-99076D01*
X521677Y-100242D01*
X519930Y-101117D01*
X515564D01*
G01X534592Y-93242D02*
X541579D01*
X540924Y-91200D01*
X539832Y-90034D01*
X538304Y-89451D01*
X536775Y-89742D01*
X535465Y-90617D01*
X534592Y-92659D01*
X534155Y-94409D01*
Y-96159D01*
X534592Y-97909D01*
X535684Y-99659D01*
X536994Y-100825D01*
X538522Y-101117D01*
X540050Y-100534D01*
X541579Y-98784D01*
G01X552092Y-99076D02*
X553184Y-100242D01*
X554712Y-101117D01*
X556022D01*
X557332Y-100534D01*
X558205Y-99659D01*
X558642Y-98493D01*
X558424Y-96742D01*
X557550Y-95867D01*
X553620Y-94117D01*
X552747Y-92075D01*
X553184Y-90617D01*
X554057Y-89742D01*
X555367Y-89451D01*
X556677Y-89742D01*
X557987Y-90617D01*
G01X572867Y-89451D02*
Y-101117D01*
G01Y-84784D02*
X572430Y-84492D01*
Y-83909D01*
X572867Y-83617D01*
X573304Y-83909D01*
Y-84492D01*
X572867Y-84784D01*
G01X587310Y-105492D02*
X588839Y-106659D01*
X590585Y-106950D01*
X592113Y-106659D01*
X593424Y-105201D01*
X594297Y-103159D01*
Y-89451D01*
G01Y-91784D02*
X593424Y-90617D01*
X592113Y-89742D01*
X590585Y-89451D01*
X588839Y-90034D01*
X587747Y-91200D01*
X586873Y-93242D01*
X586437Y-95284D01*
X586655Y-97034D01*
X587529Y-99076D01*
X588839Y-100534D01*
X590585Y-101117D01*
X591895Y-100825D01*
X593424Y-99659D01*
X594297Y-98493D01*
G01X604155Y-101117D02*
Y-89451D01*
G01Y-92367D02*
X605029Y-90909D01*
X606339Y-89742D01*
X608085Y-89451D01*
X609613Y-89742D01*
X610924Y-90909D01*
X611579Y-92950D01*
Y-101117D01*
G01X622092Y-93242D02*
X629079D01*
X628424Y-91200D01*
X627332Y-90034D01*
X625804Y-89451D01*
X624275Y-89742D01*
X622965Y-90617D01*
X622092Y-92659D01*
X621655Y-94409D01*
Y-96159D01*
X622092Y-97909D01*
X623184Y-99659D01*
X624494Y-100825D01*
X626022Y-101117D01*
X627550Y-100534D01*
X629079Y-98784D01*
G01X639810Y-101117D02*
Y-89451D01*
G01Y-91784D02*
X640902Y-90617D01*
X641994Y-89742D01*
X643522Y-89451D01*
X644613Y-89742D01*
X645924Y-90617D01*
G01X559969Y-128617D02*
X568265D01*
X559969Y-146117D01*
X568265D01*
G01X581617D02*
X579870Y-145825D01*
X578342Y-144659D01*
X577032Y-142909D01*
X576158Y-140867D01*
X575722Y-138534D01*
Y-136200D01*
X576158Y-133867D01*
X577032Y-131825D01*
X578342Y-130076D01*
X579870Y-128909D01*
X581617Y-128617D01*
X583363Y-128909D01*
X584892Y-130076D01*
X586202Y-131825D01*
X587076Y-133867D01*
X587512Y-136200D01*
Y-138534D01*
X587076Y-140867D01*
X586202Y-142909D01*
X584892Y-144659D01*
X583363Y-145825D01*
X581617Y-146117D01*
G01X603484D02*
X594750D01*
Y-128617D01*
X603484D01*
G01X599990Y-137075D02*
X594750D01*
G01X686567Y-128617D02*
X684820Y-129200D01*
X683510Y-130659D01*
X682637Y-132408D01*
X681982Y-134742D01*
X681764Y-137367D01*
X681982Y-139992D01*
X682637Y-142326D01*
X683510Y-144076D01*
X684820Y-145534D01*
X686567Y-146117D01*
X688313Y-145534D01*
X689624Y-144076D01*
X690497Y-142326D01*
X691152Y-139992D01*
X691370Y-137367D01*
X691152Y-134742D01*
X690497Y-132408D01*
X689624Y-130659D01*
X688313Y-129200D01*
X686567Y-128617D01*
G01X699919Y-131534D02*
X701229Y-129784D01*
X702757Y-128909D01*
X704504Y-128617D01*
X706687Y-129200D01*
X708215Y-130659D01*
X708652Y-132408D01*
X708434Y-134159D01*
X707560Y-135617D01*
X703194Y-138534D01*
X701229Y-140575D01*
X699919Y-143493D01*
X699482Y-146117D01*
X708652D01*
G01X717637Y-146700D02*
X725497Y-128617D01*
G01X739067D02*
X737320Y-129200D01*
X736010Y-130659D01*
X735137Y-132408D01*
X734482Y-134742D01*
X734264Y-137367D01*
X734482Y-139992D01*
X735137Y-142326D01*
X736010Y-144076D01*
X737320Y-145534D01*
X739067Y-146117D01*
X740813Y-145534D01*
X742124Y-144076D01*
X742997Y-142326D01*
X743652Y-139992D01*
X743870Y-137367D01*
X743652Y-134742D01*
X742997Y-132408D01*
X742124Y-130659D01*
X740813Y-129200D01*
X739067Y-128617D01*
G01X756130Y-146117D02*
X756567Y-142326D01*
X757222Y-139117D01*
X758095Y-136200D01*
X759187Y-132992D01*
X760934Y-128617D01*
X752200D01*
G01X770137Y-146700D02*
X777997Y-128617D01*
G01X787419Y-131534D02*
X788729Y-129784D01*
X790257Y-128909D01*
X792004Y-128617D01*
X794187Y-129200D01*
X795715Y-130659D01*
X796152Y-132408D01*
X795934Y-134159D01*
X795060Y-135617D01*
X790694Y-138534D01*
X788729Y-140575D01*
X787419Y-143493D01*
X786982Y-146117D01*
X796152D01*
G01X809067Y-128617D02*
X807320Y-129200D01*
X806010Y-130659D01*
X805137Y-132408D01*
X804482Y-134742D01*
X804264Y-137367D01*
X804482Y-139992D01*
X805137Y-142326D01*
X806010Y-144076D01*
X807320Y-145534D01*
X809067Y-146117D01*
X810813Y-145534D01*
X812124Y-144076D01*
X812997Y-142326D01*
X813652Y-139992D01*
X813870Y-137367D01*
X813652Y-134742D01*
X812997Y-132408D01*
X812124Y-130659D01*
X810813Y-129200D01*
X809067Y-128617D01*
G01X826567Y-146117D02*
Y-128617D01*
X823947Y-132117D01*
G01Y-146117D02*
X829187D01*
G01X843630D02*
X844067Y-142326D01*
X844722Y-139117D01*
X845595Y-136200D01*
X846687Y-132992D01*
X848434Y-128617D01*
X839700D01*
G01X734264Y-101117D02*
Y-83617D01*
X738630D01*
X740377Y-84492D01*
X741687Y-85659D01*
X742779Y-87408D01*
X743652Y-89451D01*
X743870Y-92367D01*
X743652Y-95284D01*
X742779Y-97326D01*
X741687Y-99076D01*
X740377Y-100242D01*
X738630Y-101117D01*
X734264D01*
G01X760497D02*
Y-89451D01*
G01Y-91492D02*
X759624Y-90326D01*
X758313Y-89742D01*
X756785Y-89451D01*
X755257Y-90034D01*
X753947Y-91200D01*
X753073Y-92950D01*
X752637Y-95284D01*
X753073Y-97617D01*
X753947Y-99367D01*
X755257Y-100534D01*
X756785Y-101117D01*
X758313Y-100825D01*
X759624Y-99951D01*
X760497Y-98784D01*
G01X774067Y-83617D02*
Y-101117D01*
G01X771010Y-89451D02*
X777124D01*
G01X788292Y-93242D02*
X795279D01*
X794624Y-91200D01*
X793532Y-90034D01*
X792004Y-89451D01*
X790475Y-89742D01*
X789165Y-90617D01*
X788292Y-92659D01*
X787855Y-94409D01*
Y-96159D01*
X788292Y-97909D01*
X789384Y-99659D01*
X790694Y-100825D01*
X792222Y-101117D01*
X793750Y-100534D01*
X795279Y-98784D01*
G01X0Y-11811D02*
G03X7874Y-19685I7874J0D01*
G01X37008Y0D02*
G03Y-7874I0J-3937D01*
G01X11811D02*
G03Y0I0J3937D01*
G01X0Y-7874D02*
Y-11811D01*
G01X7874Y-19685D02*
X181690D01*
G01X0Y-7874D02*
X11811D01*
G01X25985Y19685D02*
G03X9449I-8268J0D01*
G01D02*
G03X25985I8268J0D01*
G01D02*
G03X9449I-8268J0D01*
G01D02*
G03X25985I8268J0D01*
G01D02*
G03X9449I-8268J0D01*
G01D02*
G03X25985I8268J0D01*
G01D02*
G03X9449I-8268J0D01*
G01D02*
G03X25985I8268J0D01*
G01X9449D02*
G03X25985I8268J0D01*
G01D02*
G03X9449I-8268J0D01*
G01D02*
G03X25985I8268J0D01*
G01D02*
G03X9449I-8268J0D01*
G01X3937Y0D02*
X173229D01*
G01X0Y3937D02*
G03X3937Y0I3937J0D01*
G01X0Y57874D02*
Y3937D01*
G01X37008Y69685D02*
G03Y61811I0J-3937D01*
G01X11811D02*
G03Y69685I0J3937D01*
G01X25985Y89370D02*
G03X9449I-8268J0D01*
G01D02*
G03X25985I8268J0D01*
G01D02*
G03X9449I-8268J0D01*
G01D02*
G03X25985I8268J0D01*
G01D02*
G03X9449I-8268J0D01*
G01D02*
G03X25985I8268J0D01*
G01D02*
G03X9449I-8268J0D01*
G01D02*
G03X25985I8268J0D01*
G01X9449D02*
G03X25985I8268J0D01*
G01D02*
G03X9449I-8268J0D01*
G01D02*
G03X25985I8268J0D01*
G01D02*
G03X9449I-8268J0D01*
G01X3937Y69685D02*
X173229D01*
G01X0Y73622D02*
G03X3937Y69685I3937J0D01*
G01X0Y127559D02*
Y73622D01*
G01X3937Y61811D02*
G03X0Y57874I0J-3937D01*
G01X173229Y61811D02*
X3937D01*
G01X37008Y139370D02*
G03Y131496I0J-3937D01*
G01X11811D02*
G03Y139370I0J3937D01*
G01X25985Y159055D02*
G03X9449I-8268J0D01*
G01D02*
G03X25985I8268J0D01*
G01D02*
G03X9449I-8268J0D01*
G01D02*
G03X25985I8268J0D01*
G01D02*
G03X9449I-8268J0D01*
G01D02*
G03X25985I8268J0D01*
G01D02*
G03X9449I-8268J0D01*
G01D02*
G03X25985I8268J0D01*
G01X9449D02*
G03X25985I8268J0D01*
G01D02*
G03X9449I-8268J0D01*
G01D02*
G03X25985I8268J0D01*
G01D02*
G03X9449I-8268J0D01*
G01X3937Y139370D02*
X173229D01*
G01X0Y143307D02*
G03X3937Y139370I3937J0D01*
G01X0Y197244D02*
Y143307D01*
G01X3937Y131496D02*
G03X0Y127559I0J-3937D01*
G01X173229Y131496D02*
X3937D01*
G01X37008Y278740D02*
G03Y270866I0J-3937D01*
G01X11811D02*
G03Y278740I0J3937D01*
G01X37008Y209055D02*
G03Y201181I0J-3937D01*
G01X11811D02*
G03Y209055I0J3937D01*
G01X3937Y278740D02*
X173229D01*
G01X0Y282677D02*
G03X3937Y278740I3937J0D01*
G01X25985Y228740D02*
G03X9449I-8268J0D01*
G01D02*
G03X25985I8268J0D01*
G01D02*
G03X9449I-8268J0D01*
G01D02*
G03X25985I8268J0D01*
G01D02*
G03X9449I-8268J0D01*
G01D02*
G03X25985I8268J0D01*
G01D02*
G03X9449I-8268J0D01*
G01D02*
G03X25985I8268J0D01*
G01X9449D02*
G03X25985I8268J0D01*
G01D02*
G03X9449I-8268J0D01*
G01D02*
G03X25985I8268J0D01*
G01D02*
G03X9449I-8268J0D01*
G01X3937Y209055D02*
X173229D01*
G01X0Y212992D02*
G03X3937Y209055I3937J0D01*
G01X0Y266929D02*
Y212992D01*
G01X3937Y270866D02*
G03X0Y266929I0J-3937D01*
G01X173229Y270866D02*
X3937D01*
G01Y201181D02*
G03X0Y197244I0J-3937D01*
G01X173229Y201181D02*
X3937D01*
G01X37008Y348425D02*
G03Y340551I0J-3937D01*
G01X11811D02*
G03Y348425I0J3937D01*
G01X9449Y368110D02*
G03X25985I8268J0D01*
G01X9449D02*
G03X25985I8268J0D01*
G01X9449D02*
G03X25985I8268J0D01*
G01X9449D02*
G03X25985I8268J0D01*
G01X9449D02*
G03X25985I8268J0D01*
G01X9449D02*
G03X25985I8268J0D01*
G01X3937Y348425D02*
X173229D01*
G01X0Y352362D02*
G03X3937Y348425I3937J0D01*
G01X0Y406299D02*
Y352362D01*
G01X25985Y298425D02*
G03X9449I-8268J0D01*
G01D02*
G03X25985I8268J0D01*
G01D02*
G03X9449I-8268J0D01*
G01D02*
G03X25985I8268J0D01*
G01D02*
G03X9449I-8268J0D01*
G01D02*
G03X25985I8268J0D01*
G01D02*
G03X9449I-8268J0D01*
G01D02*
G03X25985I8268J0D01*
G01X9449D02*
G03X25985I8268J0D01*
G01D02*
G03X9449I-8268J0D01*
G01D02*
G03X25985I8268J0D01*
G01D02*
G03X9449I-8268J0D01*
G01X0Y336614D02*
Y282677D01*
G01X3937Y340551D02*
G03X0Y336614I0J-3937D01*
G01X173229Y340551D02*
X3937D01*
G01X37008Y418110D02*
G03Y410236I0J-3937D01*
G01X11811D02*
G03Y418110I0J3937D01*
G01X25985Y437795D02*
G03X9449I-8268J0D01*
G01D02*
G03X25985I8268J0D01*
G01D02*
G03X9449I-8268J0D01*
G01D02*
G03X25985I8268J0D01*
G01D02*
G03X9449I-8268J0D01*
G01D02*
G03X25985I8268J0D01*
G01D02*
G03X9449I-8268J0D01*
G01D02*
G03X25985I8268J0D01*
G01X9449D02*
G03X25985I8268J0D01*
G01D02*
G03X9449I-8268J0D01*
G01D02*
G03X25985I8268J0D01*
G01D02*
G03X9449I-8268J0D01*
G01X3937Y418110D02*
X173229D01*
G01X0Y422047D02*
G03X3937Y418110I3937J0D01*
G01X0Y475984D02*
Y422047D01*
G01X25985Y368110D02*
G03X9449I-8268J0D01*
G01X25985D02*
G03X9449I-8268J0D01*
G01X25985D02*
G03X9449I-8268J0D01*
G01X25985D02*
G03X9449I-8268J0D01*
G01X25985D02*
G03X9449I-8268J0D01*
G01X25985D02*
G03X9449I-8268J0D01*
G01X3937Y410236D02*
G03X0Y406299I0J-3937D01*
G01X173229Y410236D02*
X3937D01*
G01X37008Y487795D02*
G03Y479921I0J-3937D01*
G01X11811D02*
G03Y487795I0J3937D01*
G01X25985Y507480D02*
G03X9449I-8268J0D01*
G01D02*
G03X25985I8268J0D01*
G01D02*
G03X9449I-8268J0D01*
G01D02*
G03X25985I8268J0D01*
G01D02*
G03X9449I-8268J0D01*
G01D02*
G03X25985I8268J0D01*
G01D02*
G03X9449I-8268J0D01*
G01D02*
G03X25985I8268J0D01*
G01X9449D02*
G03X25985I8268J0D01*
G01D02*
G03X9449I-8268J0D01*
G01D02*
G03X25985I8268J0D01*
G01D02*
G03X9449I-8268J0D01*
G01X3937Y487795D02*
X173229D01*
G01X0Y491732D02*
G03X3937Y487795I3937J0D01*
G01X0Y545669D02*
Y491732D01*
G01X3937Y479921D02*
G03X0Y475984I0J-3937D01*
G01X173229Y479921D02*
X3937D01*
G01X37008Y557480D02*
G03Y549606I0J-3937D01*
G01X11811D02*
G03Y557480I0J3937D01*
G01X25985Y577165D02*
G03X9449I-8268J0D01*
G01D02*
G03X25985I8268J0D01*
G01D02*
G03X9449I-8268J0D01*
G01D02*
G03X25985I8268J0D01*
G01D02*
G03X9449I-8268J0D01*
G01D02*
G03X25985I8268J0D01*
G01D02*
G03X9449I-8268J0D01*
G01D02*
G03X25985I8268J0D01*
G01X9449D02*
G03X25985I8268J0D01*
G01D02*
G03X9449I-8268J0D01*
G01D02*
G03X25985I8268J0D01*
G01D02*
G03X9449I-8268J0D01*
G01X3937Y557480D02*
X173229D01*
G01X0Y561417D02*
G03X3937Y557480I3937J0D01*
G01X0Y615354D02*
Y561417D01*
G01X3937Y549606D02*
G03X0Y545669I0J-3937D01*
G01X173229Y549606D02*
X3937D01*
G01X37008Y627165D02*
G03Y619291I0J-3937D01*
G01X11811D02*
G03Y627165I0J3937D01*
G01X25985Y646850D02*
G03X9449I-8268J0D01*
G01D02*
G03X25985I8268J0D01*
G01D02*
G03X9449I-8268J0D01*
G01D02*
G03X25985I8268J0D01*
G01D02*
G03X9449I-8268J0D01*
G01D02*
G03X25985I8268J0D01*
G01D02*
G03X9449I-8268J0D01*
G01D02*
G03X25985I8268J0D01*
G01X9449D02*
G03X25985I8268J0D01*
G01D02*
G03X9449I-8268J0D01*
G01D02*
G03X25985I8268J0D01*
G01D02*
G03X9449I-8268J0D01*
G01X3937Y627165D02*
X173229D01*
G01X0Y631102D02*
G03X3937Y627165I3937J0D01*
G01X0Y685039D02*
Y631102D01*
G01X3937Y688976D02*
G03X0Y685039I0J-3937D01*
G01X173229Y688976D02*
X3937D01*
G01Y619291D02*
G03X0Y615354I0J-3937D01*
G01X173229Y619291D02*
X3937D01*
G01X37008Y-7874D02*
X140158D01*
G01X196851D02*
G03Y0I0J3937D01*
G01X189564Y-19685D02*
G03X181690I-3937J0D01*
G01X165355Y0D02*
G03Y-7874I0J-3937D01*
G01X140158D02*
G03Y0I0J3937D01*
G01X185040Y18307D02*
G03X177166I-3937J0D01*
G01X189564Y-19685D02*
X539370D01*
G01X165355Y-7874D02*
X196851D01*
G01X211024Y19685D02*
G03X194489I-8267J0D01*
G01D02*
G03X211024I8267J0D01*
G01D02*
G03X194489I-8267J0D01*
G01D02*
G03X211024I8267J0D01*
G01D02*
G03X194489I-8267J0D01*
G01D02*
G03X211024I8267J0D01*
G01D02*
G03X194489I-8267J0D01*
G01D02*
G03X211024I8267J0D01*
G01X194489D02*
G03X211024I8267J0D01*
G01D02*
G03X194489I-8267J0D01*
G01D02*
G03X211024I8267J0D01*
G01D02*
G03X194489I-8267J0D01*
G01X188977Y0D02*
X358268D01*
G01X185040Y3937D02*
G03X188977Y0I3937J0D01*
G01X185040Y57874D02*
Y3937D01*
G01X167717Y19685D02*
G03X151181I-8268J0D01*
G01D02*
G03X167717I8268J0D01*
G01D02*
G03X151181I-8268J0D01*
G01D02*
G03X167717I8268J0D01*
G01D02*
G03X151181I-8268J0D01*
G01D02*
G03X167717I8268J0D01*
G01D02*
G03X151181I-8268J0D01*
G01D02*
G03X167717I8268J0D01*
G01X151181D02*
G03X167717I8268J0D01*
G01D02*
G03X151181I-8268J0D01*
G01D02*
G03X167717I8268J0D01*
G01D02*
G03X151181I-8268J0D01*
G01X177166Y3937D02*
Y57874D01*
G01X173229Y0D02*
G03X177166Y3937I0J3937D01*
G01X185040Y87992D02*
G03X177166I-3937J0D01*
G01Y113189D02*
G03X185040I3937J0D01*
G01X196851Y61811D02*
G03Y69685I0J3937D01*
G01X165355D02*
G03Y61811I0J-3937D01*
G01X140158D02*
G03Y69685I0J3937D01*
G01X177166Y43504D02*
G03X185040I3937J0D01*
G01X167717Y89370D02*
G03X151181I-8268J0D01*
G01D02*
G03X167717I8268J0D01*
G01D02*
G03X151181I-8268J0D01*
G01D02*
G03X167717I8268J0D01*
G01D02*
G03X151181I-8268J0D01*
G01D02*
G03X167717I8268J0D01*
G01D02*
G03X151181I-8268J0D01*
G01D02*
G03X167717I8268J0D01*
G01X151181D02*
G03X167717I8268J0D01*
G01D02*
G03X151181I-8268J0D01*
G01D02*
G03X167717I8268J0D01*
G01D02*
G03X151181I-8268J0D01*
G01X177166Y73622D02*
Y127559D01*
G01X173229Y69685D02*
G03X177166Y73622I0J3937D01*
G01X211024Y89370D02*
G03X194489I-8267J0D01*
G01D02*
G03X211024I8267J0D01*
G01D02*
G03X194489I-8267J0D01*
G01D02*
G03X211024I8267J0D01*
G01D02*
G03X194489I-8267J0D01*
G01D02*
G03X211024I8267J0D01*
G01D02*
G03X194489I-8267J0D01*
G01D02*
G03X211024I8267J0D01*
G01X194489D02*
G03X211024I8267J0D01*
G01D02*
G03X194489I-8267J0D01*
G01D02*
G03X211024I8267J0D01*
G01D02*
G03X194489I-8267J0D01*
G01X188977Y69685D02*
X358268D01*
G01X185040Y73622D02*
G03X188977Y69685I3937J0D01*
G01X185040Y127559D02*
Y73622D01*
G01X188977Y61811D02*
G03X185040Y57874I0J-3937D01*
G01X358268Y61811D02*
X188977D01*
G01X177166Y57874D02*
G03X173229Y61811I-3937J0D01*
G01X185040Y157677D02*
G03X177166I-3937J0D01*
G01Y182874D02*
G03X185040I3937J0D01*
G01X196851Y131496D02*
G03Y139370I0J3937D01*
G01X165355D02*
G03Y131496I0J-3937D01*
G01X140158D02*
G03Y139370I0J3937D01*
G01X167717Y159055D02*
G03X151181I-8268J0D01*
G01D02*
G03X167717I8268J0D01*
G01D02*
G03X151181I-8268J0D01*
G01D02*
G03X167717I8268J0D01*
G01D02*
G03X151181I-8268J0D01*
G01D02*
G03X167717I8268J0D01*
G01D02*
G03X151181I-8268J0D01*
G01D02*
G03X167717I8268J0D01*
G01X151181D02*
G03X167717I8268J0D01*
G01D02*
G03X151181I-8268J0D01*
G01D02*
G03X167717I8268J0D01*
G01D02*
G03X151181I-8268J0D01*
G01X177166Y143307D02*
Y197244D01*
G01X173229Y139370D02*
G03X177166Y143307I0J3937D01*
G01Y127559D02*
G03X173229Y131496I-3937J0D01*
G01X211024Y159055D02*
G03X194489I-8267J0D01*
G01D02*
G03X211024I8267J0D01*
G01D02*
G03X194489I-8267J0D01*
G01D02*
G03X211024I8267J0D01*
G01D02*
G03X194489I-8267J0D01*
G01D02*
G03X211024I8267J0D01*
G01D02*
G03X194489I-8267J0D01*
G01D02*
G03X211024I8267J0D01*
G01X194489D02*
G03X211024I8267J0D01*
G01D02*
G03X194489I-8267J0D01*
G01D02*
G03X211024I8267J0D01*
G01D02*
G03X194489I-8267J0D01*
G01X188977Y139370D02*
X358268D01*
G01X185040Y143307D02*
G03X188977Y139370I3937J0D01*
G01X185040Y197244D02*
Y143307D01*
G01X188977Y131496D02*
G03X185040Y127559I0J-3937D01*
G01X358268Y131496D02*
X188977D01*
G01X185040Y227362D02*
G03X177166I-3937J0D01*
G01Y252559D02*
G03X185040I3937J0D01*
G01X196851Y270866D02*
G03Y278740I0J3937D01*
G01X165355D02*
G03Y270866I0J-3937D01*
G01X140158D02*
G03Y278740I0J3937D01*
G01X196851Y201181D02*
G03Y209055I0J3937D01*
G01X165355D02*
G03Y201181I0J-3937D01*
G01X140158D02*
G03Y209055I0J3937D01*
G01X173229Y278740D02*
G03X177166Y282677I0J3937D01*
G01X188977Y278740D02*
X358268D01*
G01X185040Y282677D02*
G03X188977Y278740I3937J0D01*
G01X167717Y228740D02*
G03X151181I-8268J0D01*
G01D02*
G03X167717I8268J0D01*
G01D02*
G03X151181I-8268J0D01*
G01D02*
G03X167717I8268J0D01*
G01D02*
G03X151181I-8268J0D01*
G01D02*
G03X167717I8268J0D01*
G01D02*
G03X151181I-8268J0D01*
G01D02*
G03X167717I8268J0D01*
G01X151181D02*
G03X167717I8268J0D01*
G01D02*
G03X151181I-8268J0D01*
G01D02*
G03X167717I8268J0D01*
G01D02*
G03X151181I-8268J0D01*
G01X177166Y212992D02*
Y266929D01*
G01X173229Y209055D02*
G03X177166Y212992I0J3937D01*
G01Y266929D02*
G03X173229Y270866I-3937J0D01*
G01X211024Y228740D02*
G03X194489I-8267J0D01*
G01D02*
G03X211024I8267J0D01*
G01D02*
G03X194489I-8267J0D01*
G01D02*
G03X211024I8267J0D01*
G01D02*
G03X194489I-8267J0D01*
G01D02*
G03X211024I8267J0D01*
G01D02*
G03X194489I-8267J0D01*
G01D02*
G03X211024I8267J0D01*
G01X194489D02*
G03X211024I8267J0D01*
G01D02*
G03X194489I-8267J0D01*
G01D02*
G03X211024I8267J0D01*
G01D02*
G03X194489I-8267J0D01*
G01X188977Y209055D02*
X358268D01*
G01X185040Y212992D02*
G03X188977Y209055I3937J0D01*
G01X185040Y266929D02*
Y212992D01*
G01X188977Y270866D02*
G03X185040Y266929I0J-3937D01*
G01X358268Y270866D02*
X188977D01*
G01X177166Y197244D02*
G03X173229Y201181I-3937J0D01*
G01X188977D02*
G03X185040Y197244I0J-3937D01*
G01X358268Y201181D02*
X188977D01*
G01X185040Y297047D02*
G03X177166I-3937J0D01*
G01Y322244D02*
G03X185040I3937J0D01*
G01X196851Y340551D02*
G03Y348425I0J3937D01*
G01X165355D02*
G03Y340551I0J-3937D01*
G01X140158D02*
G03Y348425I0J3937D01*
G01X151181Y368110D02*
G03X167717I8268J0D01*
G01X151181D02*
G03X167717I8268J0D01*
G01X151181D02*
G03X167717I8268J0D01*
G01X151181D02*
G03X167717I8268J0D01*
G01X151181D02*
G03X167717I8268J0D01*
G01X151181D02*
G03X167717I8268J0D01*
G01X177166Y352362D02*
Y406299D01*
G01X173229Y348425D02*
G03X177166Y352362I0J3937D01*
G01X194489Y368110D02*
G03X211024I8267J0D01*
G01X194489D02*
G03X211024I8267J0D01*
G01X194489D02*
G03X211024I8267J0D01*
G01X194489D02*
G03X211024I8267J0D01*
G01X194489D02*
G03X211024I8267J0D01*
G01X194489D02*
G03X211024I8267J0D01*
G01X188977Y348425D02*
X358268D01*
G01X185040Y352362D02*
G03X188977Y348425I3937J0D01*
G01X185040Y406299D02*
Y352362D01*
G01X167717Y298425D02*
G03X151181I-8268J0D01*
G01D02*
G03X167717I8268J0D01*
G01D02*
G03X151181I-8268J0D01*
G01D02*
G03X167717I8268J0D01*
G01D02*
G03X151181I-8268J0D01*
G01D02*
G03X167717I8268J0D01*
G01D02*
G03X151181I-8268J0D01*
G01D02*
G03X167717I8268J0D01*
G01X151181D02*
G03X167717I8268J0D01*
G01D02*
G03X151181I-8268J0D01*
G01D02*
G03X167717I8268J0D01*
G01D02*
G03X151181I-8268J0D01*
G01X177166Y282677D02*
Y336614D01*
G01D02*
G03X173229Y340551I-3937J0D01*
G01X211024Y298425D02*
G03X194489I-8267J0D01*
G01D02*
G03X211024I8267J0D01*
G01D02*
G03X194489I-8267J0D01*
G01D02*
G03X211024I8267J0D01*
G01D02*
G03X194489I-8267J0D01*
G01D02*
G03X211024I8267J0D01*
G01D02*
G03X194489I-8267J0D01*
G01D02*
G03X211024I8267J0D01*
G01X194489D02*
G03X211024I8267J0D01*
G01D02*
G03X194489I-8267J0D01*
G01D02*
G03X211024I8267J0D01*
G01D02*
G03X194489I-8267J0D01*
G01X185040Y336614D02*
Y282677D01*
G01X188977Y340551D02*
G03X185040Y336614I0J-3937D01*
G01X358268Y340551D02*
X188977D01*
G01X185040Y436417D02*
G03X177166I-3937J0D01*
G01X185040Y366732D02*
G03X177166I-3937J0D01*
G01Y391929D02*
G03X185040I3937J0D01*
G01X196851Y410236D02*
G03Y418110I0J3937D01*
G01X165355D02*
G03Y410236I0J-3937D01*
G01X140158D02*
G03Y418110I0J3937D01*
G01X167717Y437795D02*
G03X151181I-8268J0D01*
G01D02*
G03X167717I8268J0D01*
G01D02*
G03X151181I-8268J0D01*
G01D02*
G03X167717I8268J0D01*
G01D02*
G03X151181I-8268J0D01*
G01D02*
G03X167717I8268J0D01*
G01D02*
G03X151181I-8268J0D01*
G01D02*
G03X167717I8268J0D01*
G01X151181D02*
G03X167717I8268J0D01*
G01D02*
G03X151181I-8268J0D01*
G01D02*
G03X167717I8268J0D01*
G01D02*
G03X151181I-8268J0D01*
G01X177166Y422047D02*
Y475984D01*
G01X173229Y418110D02*
G03X177166Y422047I0J3937D01*
G01X211024Y437795D02*
G03X194489I-8267J0D01*
G01D02*
G03X211024I8267J0D01*
G01D02*
G03X194489I-8267J0D01*
G01D02*
G03X211024I8267J0D01*
G01D02*
G03X194489I-8267J0D01*
G01D02*
G03X211024I8267J0D01*
G01D02*
G03X194489I-8267J0D01*
G01D02*
G03X211024I8267J0D01*
G01X194489D02*
G03X211024I8267J0D01*
G01D02*
G03X194489I-8267J0D01*
G01D02*
G03X211024I8267J0D01*
G01D02*
G03X194489I-8267J0D01*
G01X188977Y418110D02*
X358268D01*
G01X185040Y422047D02*
G03X188977Y418110I3937J0D01*
G01X185040Y475984D02*
Y422047D01*
G01X167717Y368110D02*
G03X151181I-8268J0D01*
G01X167717D02*
G03X151181I-8268J0D01*
G01X167717D02*
G03X151181I-8268J0D01*
G01X167717D02*
G03X151181I-8268J0D01*
G01X167717D02*
G03X151181I-8268J0D01*
G01X167717D02*
G03X151181I-8268J0D01*
G01X177166Y406299D02*
G03X173229Y410236I-3937J0D01*
G01X211024Y368110D02*
G03X194489I-8267J0D01*
G01X211024D02*
G03X194489I-8267J0D01*
G01X211024D02*
G03X194489I-8267J0D01*
G01X211024D02*
G03X194489I-8267J0D01*
G01X211024D02*
G03X194489I-8267J0D01*
G01X211024D02*
G03X194489I-8267J0D01*
G01X188977Y410236D02*
G03X185040Y406299I0J-3937D01*
G01X358268Y410236D02*
X188977D01*
G01X185040Y506102D02*
G03X177166I-3937J0D01*
G01Y531299D02*
G03X185040I3937J0D01*
G01X177166Y461614D02*
G03X185040I3937J0D01*
G01X196851Y479921D02*
G03Y487795I0J3937D01*
G01X165355D02*
G03Y479921I0J-3937D01*
G01X140158D02*
G03Y487795I0J3937D01*
G01X167717Y507480D02*
G03X151181I-8268J0D01*
G01D02*
G03X167717I8268J0D01*
G01D02*
G03X151181I-8268J0D01*
G01D02*
G03X167717I8268J0D01*
G01D02*
G03X151181I-8268J0D01*
G01D02*
G03X167717I8268J0D01*
G01D02*
G03X151181I-8268J0D01*
G01D02*
G03X167717I8268J0D01*
G01X151181D02*
G03X167717I8268J0D01*
G01D02*
G03X151181I-8268J0D01*
G01D02*
G03X167717I8268J0D01*
G01D02*
G03X151181I-8268J0D01*
G01X177166Y491732D02*
Y545669D01*
G01X173229Y487795D02*
G03X177166Y491732I0J3937D01*
G01X211024Y507480D02*
G03X194489I-8267J0D01*
G01D02*
G03X211024I8267J0D01*
G01D02*
G03X194489I-8267J0D01*
G01D02*
G03X211024I8267J0D01*
G01D02*
G03X194489I-8267J0D01*
G01D02*
G03X211024I8267J0D01*
G01D02*
G03X194489I-8267J0D01*
G01D02*
G03X211024I8267J0D01*
G01X194489D02*
G03X211024I8267J0D01*
G01D02*
G03X194489I-8267J0D01*
G01D02*
G03X211024I8267J0D01*
G01D02*
G03X194489I-8267J0D01*
G01X188977Y487795D02*
X358268D01*
G01X185040Y491732D02*
G03X188977Y487795I3937J0D01*
G01X185040Y545669D02*
Y491732D01*
G01X177166Y475984D02*
G03X173229Y479921I-3937J0D01*
G01X188977D02*
G03X185040Y475984I0J-3937D01*
G01X358268Y479921D02*
X188977D01*
G01X185040Y575787D02*
G03X177166I-3937J0D01*
G01Y600984D02*
G03X185040I3937J0D01*
G01X196851Y549606D02*
G03Y557480I0J3937D01*
G01X165355D02*
G03Y549606I0J-3937D01*
G01X140158D02*
G03Y557480I0J3937D01*
G01X167717Y577165D02*
G03X151181I-8268J0D01*
G01D02*
G03X167717I8268J0D01*
G01D02*
G03X151181I-8268J0D01*
G01D02*
G03X167717I8268J0D01*
G01D02*
G03X151181I-8268J0D01*
G01D02*
G03X167717I8268J0D01*
G01D02*
G03X151181I-8268J0D01*
G01D02*
G03X167717I8268J0D01*
G01X151181D02*
G03X167717I8268J0D01*
G01D02*
G03X151181I-8268J0D01*
G01D02*
G03X167717I8268J0D01*
G01D02*
G03X151181I-8268J0D01*
G01X177166Y561417D02*
Y615354D01*
G01X173229Y557480D02*
G03X177166Y561417I0J3937D01*
G01X211024Y577165D02*
G03X194489I-8267J0D01*
G01D02*
G03X211024I8267J0D01*
G01D02*
G03X194489I-8267J0D01*
G01D02*
G03X211024I8267J0D01*
G01D02*
G03X194489I-8267J0D01*
G01D02*
G03X211024I8267J0D01*
G01D02*
G03X194489I-8267J0D01*
G01D02*
G03X211024I8267J0D01*
G01X194489D02*
G03X211024I8267J0D01*
G01D02*
G03X194489I-8267J0D01*
G01D02*
G03X211024I8267J0D01*
G01D02*
G03X194489I-8267J0D01*
G01X188977Y557480D02*
X358268D01*
G01X185040Y561417D02*
G03X188977Y557480I3937J0D01*
G01X185040Y615354D02*
Y561417D01*
G01X177166Y545669D02*
G03X173229Y549606I-3937J0D01*
G01X188977D02*
G03X185040Y545669I0J-3937D01*
G01X358268Y549606D02*
X188977D01*
G01X185040Y645472D02*
G03X177166I-3937J0D01*
G01Y670669D02*
G03X185040I3937J0D01*
G01X196851Y619291D02*
G03Y627165I0J3937D01*
G01X165355D02*
G03Y619291I0J-3937D01*
G01X140158D02*
G03Y627165I0J3937D01*
G01X167717Y646850D02*
G03X151181I-8268J0D01*
G01D02*
G03X167717I8268J0D01*
G01D02*
G03X151181I-8268J0D01*
G01D02*
G03X167717I8268J0D01*
G01D02*
G03X151181I-8268J0D01*
G01D02*
G03X167717I8268J0D01*
G01D02*
G03X151181I-8268J0D01*
G01D02*
G03X167717I8268J0D01*
G01X151181D02*
G03X167717I8268J0D01*
G01D02*
G03X151181I-8268J0D01*
G01D02*
G03X167717I8268J0D01*
G01D02*
G03X151181I-8268J0D01*
G01X177166Y631102D02*
Y685039D01*
G01X173229Y627165D02*
G03X177166Y631102I0J3937D01*
G01Y685039D02*
G03X173229Y688976I-3937J0D01*
G01X211024Y646850D02*
G03X194489I-8267J0D01*
G01D02*
G03X211024I8267J0D01*
G01D02*
G03X194489I-8267J0D01*
G01D02*
G03X211024I8267J0D01*
G01D02*
G03X194489I-8267J0D01*
G01D02*
G03X211024I8267J0D01*
G01D02*
G03X194489I-8267J0D01*
G01D02*
G03X211024I8267J0D01*
G01X194489D02*
G03X211024I8267J0D01*
G01D02*
G03X194489I-8267J0D01*
G01D02*
G03X211024I8267J0D01*
G01D02*
G03X194489I-8267J0D01*
G01X188977Y627165D02*
X358268D01*
G01X185040Y631102D02*
G03X188977Y627165I3937J0D01*
G01X185040Y685039D02*
Y631102D01*
G01X188977Y688976D02*
G03X185040Y685039I0J-3937D01*
G01X358268Y688976D02*
X188977D01*
G01X177166Y615354D02*
G03X173229Y619291I-3937J0D01*
G01X188977D02*
G03X185040Y615354I0J-3937D01*
G01X358268Y619291D02*
X188977D01*
G01X222048Y0D02*
G03Y-7874I0J-3937D01*
G01D02*
X325197D01*
G01X222048Y69685D02*
G03Y61811I0J-3937D01*
G01Y139370D02*
G03Y131496I0J-3937D01*
G01Y278740D02*
G03Y270866I0J-3937D01*
G01Y209055D02*
G03Y201181I0J-3937D01*
G01Y348425D02*
G03Y340551I0J-3937D01*
G01Y418110D02*
G03Y410236I0J-3937D01*
G01Y487795D02*
G03Y479921I0J-3937D01*
G01Y557480D02*
G03Y549606I0J-3937D01*
G01Y627165D02*
G03Y619291I0J-3937D01*
G01X370079Y18307D02*
G03X362205I-3937J0D01*
G01X350394Y0D02*
G03Y-7874I0J-3937D01*
G01X325197D02*
G03Y0I0J3937D01*
G01X350394Y-7874D02*
X381890D01*
G01X352756Y19685D02*
G03X336221I-8267J0D01*
G01D02*
G03X352756I8268J0D01*
G01D02*
G03X336221I-8267J0D01*
G01D02*
G03X352756I8268J0D01*
G01D02*
G03X336221I-8267J0D01*
G01D02*
G03X352756I8268J0D01*
G01D02*
G03X336221I-8267J0D01*
G01D02*
G03X352756I8268J0D01*
G01X336221D02*
G03X352756I8268J0D01*
G01D02*
G03X336221I-8267J0D01*
G01D02*
G03X352756I8268J0D01*
G01D02*
G03X336221I-8267J0D01*
G01X362205Y3937D02*
Y57874D01*
G01X358268Y0D02*
G03X362205Y3937I0J3937D01*
G01X370079Y87992D02*
G03X362205I-3937J0D01*
G01Y113189D02*
G03X370079I3937J0D01*
G01X362205Y43504D02*
G03X370079I3937J0D01*
G01X350394Y69685D02*
G03Y61811I0J-3937D01*
G01X325197D02*
G03Y69685I0J3937D01*
G01X352756Y89370D02*
G03X336221I-8267J0D01*
G01D02*
G03X352756I8268J0D01*
G01D02*
G03X336221I-8267J0D01*
G01D02*
G03X352756I8268J0D01*
G01D02*
G03X336221I-8267J0D01*
G01D02*
G03X352756I8268J0D01*
G01D02*
G03X336221I-8267J0D01*
G01D02*
G03X352756I8268J0D01*
G01X336221D02*
G03X352756I8268J0D01*
G01D02*
G03X336221I-8267J0D01*
G01D02*
G03X352756I8268J0D01*
G01D02*
G03X336221I-8267J0D01*
G01X362205Y73622D02*
Y127559D01*
G01X358268Y69685D02*
G03X362205Y73622I0J3937D01*
G01Y57874D02*
G03X358268Y61811I-3937J0D01*
G01X370079Y157677D02*
G03X362205I-3937J0D01*
G01Y182874D02*
G03X370079I3937J0D01*
G01X350394Y139370D02*
G03Y131496I0J-3937D01*
G01X325197D02*
G03Y139370I0J3937D01*
G01X352756Y159055D02*
G03X336221I-8267J0D01*
G01D02*
G03X352756I8268J0D01*
G01D02*
G03X336221I-8267J0D01*
G01D02*
G03X352756I8268J0D01*
G01D02*
G03X336221I-8267J0D01*
G01D02*
G03X352756I8268J0D01*
G01D02*
G03X336221I-8267J0D01*
G01D02*
G03X352756I8268J0D01*
G01X336221D02*
G03X352756I8268J0D01*
G01D02*
G03X336221I-8267J0D01*
G01D02*
G03X352756I8268J0D01*
G01D02*
G03X336221I-8267J0D01*
G01X362205Y143307D02*
Y197244D01*
G01X358268Y139370D02*
G03X362205Y143307I0J3937D01*
G01Y127559D02*
G03X358268Y131496I-3937J0D01*
G01X370079Y227362D02*
G03X362205I-3937J0D01*
G01Y252559D02*
G03X370079I3937J0D01*
G01X350394Y278740D02*
G03Y270866I0J-3937D01*
G01X325197D02*
G03Y278740I0J3937D01*
G01X350394Y209055D02*
G03Y201181I0J-3937D01*
G01X325197D02*
G03Y209055I0J3937D01*
G01X358268Y278740D02*
G03X362205Y282677I0J3937D01*
G01X352756Y228740D02*
G03X336221I-8267J0D01*
G01D02*
G03X352756I8268J0D01*
G01D02*
G03X336221I-8267J0D01*
G01D02*
G03X352756I8268J0D01*
G01D02*
G03X336221I-8267J0D01*
G01D02*
G03X352756I8268J0D01*
G01D02*
G03X336221I-8267J0D01*
G01D02*
G03X352756I8268J0D01*
G01X336221D02*
G03X352756I8268J0D01*
G01D02*
G03X336221I-8267J0D01*
G01D02*
G03X352756I8268J0D01*
G01D02*
G03X336221I-8267J0D01*
G01X362205Y212992D02*
Y266929D01*
G01X358268Y209055D02*
G03X362205Y212992I0J3937D01*
G01Y266929D02*
G03X358268Y270866I-3937J0D01*
G01X362205Y197244D02*
G03X358268Y201181I-3937J0D01*
G01X370079Y297047D02*
G03X362205I-3937J0D01*
G01Y322244D02*
G03X370079I3937J0D01*
G01X350394Y348425D02*
G03Y340551I0J-3937D01*
G01X325197D02*
G03Y348425I0J3937D01*
G01X336221Y368110D02*
G03X352756I8268J0D01*
G01X336221D02*
G03X352756I8268J0D01*
G01X336221D02*
G03X352756I8268J0D01*
G01X336221D02*
G03X352756I8268J0D01*
G01X336221D02*
G03X352756I8268J0D01*
G01X336221D02*
G03X352756I8268J0D01*
G01X362205Y352362D02*
Y406299D01*
G01X358268Y348425D02*
G03X362205Y352362I0J3937D01*
G01X352756Y298425D02*
G03X336221I-8267J0D01*
G01D02*
G03X352756I8268J0D01*
G01D02*
G03X336221I-8267J0D01*
G01D02*
G03X352756I8268J0D01*
G01D02*
G03X336221I-8267J0D01*
G01D02*
G03X352756I8268J0D01*
G01D02*
G03X336221I-8267J0D01*
G01D02*
G03X352756I8268J0D01*
G01X336221D02*
G03X352756I8268J0D01*
G01D02*
G03X336221I-8267J0D01*
G01D02*
G03X352756I8268J0D01*
G01D02*
G03X336221I-8267J0D01*
G01X362205Y282677D02*
Y336614D01*
G01D02*
G03X358268Y340551I-3937J0D01*
G01X370079Y436417D02*
G03X362205I-3937J0D01*
G01X370079Y366732D02*
G03X362205I-3937J0D01*
G01Y391929D02*
G03X370079I3937J0D01*
G01X350394Y418110D02*
G03Y410236I0J-3937D01*
G01X325197D02*
G03Y418110I0J3937D01*
G01X352756Y437795D02*
G03X336221I-8267J0D01*
G01D02*
G03X352756I8268J0D01*
G01D02*
G03X336221I-8267J0D01*
G01D02*
G03X352756I8268J0D01*
G01D02*
G03X336221I-8267J0D01*
G01D02*
G03X352756I8268J0D01*
G01D02*
G03X336221I-8267J0D01*
G01D02*
G03X352756I8268J0D01*
G01X336221D02*
G03X352756I8268J0D01*
G01D02*
G03X336221I-8267J0D01*
G01D02*
G03X352756I8268J0D01*
G01D02*
G03X336221I-8267J0D01*
G01X362205Y422047D02*
Y475984D01*
G01X358268Y418110D02*
G03X362205Y422047I0J3937D01*
G01X352756Y368110D02*
G03X336221I-8267J0D01*
G01X352756D02*
G03X336221I-8267J0D01*
G01X352756D02*
G03X336221I-8267J0D01*
G01X352756D02*
G03X336221I-8267J0D01*
G01X352756D02*
G03X336221I-8267J0D01*
G01X352756D02*
G03X336221I-8267J0D01*
G01X362205Y406299D02*
G03X358268Y410236I-3937J0D01*
G01X370079Y506102D02*
G03X362205I-3937J0D01*
G01Y531299D02*
G03X370079I3937J0D01*
G01X362205Y461614D02*
G03X370079I3937J0D01*
G01X350394Y487795D02*
G03Y479921I0J-3937D01*
G01X325197D02*
G03Y487795I0J3937D01*
G01X352756Y507480D02*
G03X336221I-8267J0D01*
G01D02*
G03X352756I8268J0D01*
G01D02*
G03X336221I-8267J0D01*
G01D02*
G03X352756I8268J0D01*
G01D02*
G03X336221I-8267J0D01*
G01D02*
G03X352756I8268J0D01*
G01D02*
G03X336221I-8267J0D01*
G01D02*
G03X352756I8268J0D01*
G01X336221D02*
G03X352756I8268J0D01*
G01D02*
G03X336221I-8267J0D01*
G01D02*
G03X352756I8268J0D01*
G01D02*
G03X336221I-8267J0D01*
G01X362205Y491732D02*
Y545669D01*
G01X358268Y487795D02*
G03X362205Y491732I0J3937D01*
G01Y475984D02*
G03X358268Y479921I-3937J0D01*
G01X370079Y575787D02*
G03X362205I-3937J0D01*
G01Y600984D02*
G03X370079I3937J0D01*
G01X350394Y557480D02*
G03Y549606I0J-3937D01*
G01X325197D02*
G03Y557480I0J3937D01*
G01X352756Y577165D02*
G03X336221I-8267J0D01*
G01D02*
G03X352756I8268J0D01*
G01D02*
G03X336221I-8267J0D01*
G01D02*
G03X352756I8268J0D01*
G01D02*
G03X336221I-8267J0D01*
G01D02*
G03X352756I8268J0D01*
G01D02*
G03X336221I-8267J0D01*
G01D02*
G03X352756I8268J0D01*
G01X336221D02*
G03X352756I8268J0D01*
G01D02*
G03X336221I-8267J0D01*
G01D02*
G03X352756I8268J0D01*
G01D02*
G03X336221I-8267J0D01*
G01X362205Y561417D02*
Y615354D01*
G01X358268Y557480D02*
G03X362205Y561417I0J3937D01*
G01Y545669D02*
G03X358268Y549606I-3937J0D01*
G01X370079Y645472D02*
G03X362205I-3937J0D01*
G01Y670669D02*
G03X370079I3937J0D01*
G01X350394Y627165D02*
G03Y619291I0J-3937D01*
G01X325197D02*
G03Y627165I0J3937D01*
G01X352756Y646850D02*
G03X336221I-8267J0D01*
G01D02*
G03X352756I8268J0D01*
G01D02*
G03X336221I-8267J0D01*
G01D02*
G03X352756I8268J0D01*
G01D02*
G03X336221I-8267J0D01*
G01D02*
G03X352756I8268J0D01*
G01D02*
G03X336221I-8267J0D01*
G01D02*
G03X352756I8268J0D01*
G01X336221D02*
G03X352756I8268J0D01*
G01D02*
G03X336221I-8267J0D01*
G01D02*
G03X352756I8268J0D01*
G01D02*
G03X336221I-8267J0D01*
G01X362205Y631102D02*
Y685039D01*
G01X358268Y627165D02*
G03X362205Y631102I0J3937D01*
G01Y685039D02*
G03X358268Y688976I-3937J0D01*
G01X362205Y615354D02*
G03X358268Y619291I-3937J0D01*
G01X407087Y0D02*
G03Y-7874I0J-3937D01*
G01X381890D02*
G03Y0I0J3937D01*
G01X407087Y-7874D02*
X510237D01*
G01X396063Y19685D02*
G03X379528I-8268J0D01*
G01D02*
G03X396063I8267J0D01*
G01D02*
G03X379528I-8268J0D01*
G01D02*
G03X396063I8267J0D01*
G01D02*
G03X379528I-8268J0D01*
G01D02*
G03X396063I8267J0D01*
G01D02*
G03X379528I-8268J0D01*
G01D02*
G03X396063I8267J0D01*
G01X379528D02*
G03X396063I8267J0D01*
G01D02*
G03X379528I-8268J0D01*
G01D02*
G03X396063I8267J0D01*
G01D02*
G03X379528I-8268J0D01*
G01X374016Y0D02*
X543307D01*
G01X370079Y3937D02*
G03X374016Y0I3937J0D01*
G01X370079Y57874D02*
Y3937D01*
G01X407087Y69685D02*
G03Y61811I0J-3937D01*
G01X381890D02*
G03Y69685I0J3937D01*
G01X396063Y89370D02*
G03X379528I-8268J0D01*
G01D02*
G03X396063I8267J0D01*
G01D02*
G03X379528I-8268J0D01*
G01D02*
G03X396063I8267J0D01*
G01D02*
G03X379528I-8268J0D01*
G01D02*
G03X396063I8267J0D01*
G01D02*
G03X379528I-8268J0D01*
G01D02*
G03X396063I8267J0D01*
G01X379528D02*
G03X396063I8267J0D01*
G01D02*
G03X379528I-8268J0D01*
G01D02*
G03X396063I8267J0D01*
G01D02*
G03X379528I-8268J0D01*
G01X374016Y69685D02*
X543307D01*
G01X370079Y73622D02*
G03X374016Y69685I3937J0D01*
G01X370079Y127559D02*
Y73622D01*
G01X374016Y61811D02*
G03X370079Y57874I0J-3937D01*
G01X543307Y61811D02*
X374016D01*
G01X407087Y139370D02*
G03Y131496I0J-3937D01*
G01X381890D02*
G03Y139370I0J3937D01*
G01X396063Y159055D02*
G03X379528I-8268J0D01*
G01D02*
G03X396063I8267J0D01*
G01D02*
G03X379528I-8268J0D01*
G01D02*
G03X396063I8267J0D01*
G01D02*
G03X379528I-8268J0D01*
G01D02*
G03X396063I8267J0D01*
G01D02*
G03X379528I-8268J0D01*
G01D02*
G03X396063I8267J0D01*
G01X379528D02*
G03X396063I8267J0D01*
G01D02*
G03X379528I-8268J0D01*
G01D02*
G03X396063I8267J0D01*
G01D02*
G03X379528I-8268J0D01*
G01X374016Y139370D02*
X543307D01*
G01X370079Y143307D02*
G03X374016Y139370I3937J0D01*
G01X370079Y197244D02*
Y143307D01*
G01X374016Y131496D02*
G03X370079Y127559I0J-3937D01*
G01X543307Y131496D02*
X374016D01*
G01X407087Y278740D02*
G03Y270866I0J-3937D01*
G01X381890D02*
G03Y278740I0J3937D01*
G01X407087Y209055D02*
G03Y201181I0J-3937D01*
G01X381890D02*
G03Y209055I0J3937D01*
G01X374016Y278740D02*
X543307D01*
G01X370079Y282677D02*
G03X374016Y278740I3937J0D01*
G01X396063Y228740D02*
G03X379528I-8268J0D01*
G01D02*
G03X396063I8267J0D01*
G01D02*
G03X379528I-8268J0D01*
G01D02*
G03X396063I8267J0D01*
G01D02*
G03X379528I-8268J0D01*
G01D02*
G03X396063I8267J0D01*
G01D02*
G03X379528I-8268J0D01*
G01D02*
G03X396063I8267J0D01*
G01X379528D02*
G03X396063I8267J0D01*
G01D02*
G03X379528I-8268J0D01*
G01D02*
G03X396063I8267J0D01*
G01D02*
G03X379528I-8268J0D01*
G01X374016Y209055D02*
X543307D01*
G01X370079Y212992D02*
G03X374016Y209055I3937J0D01*
G01X370079Y266929D02*
Y212992D01*
G01X374016Y270866D02*
G03X370079Y266929I0J-3937D01*
G01X543307Y270866D02*
X374016D01*
G01Y201181D02*
G03X370079Y197244I0J-3937D01*
G01X543307Y201181D02*
X374016D01*
G01X407087Y348425D02*
G03Y340551I0J-3937D01*
G01X381890D02*
G03Y348425I0J3937D01*
G01X379528Y368110D02*
G03X396063I8267J0D01*
G01X379528D02*
G03X396063I8267J0D01*
G01X379528D02*
G03X396063I8267J0D01*
G01X379528D02*
G03X396063I8267J0D01*
G01X379528D02*
G03X396063I8267J0D01*
G01X379528D02*
G03X396063I8267J0D01*
G01X374016Y348425D02*
X543307D01*
G01X370079Y352362D02*
G03X374016Y348425I3937J0D01*
G01X370079Y406299D02*
Y352362D01*
G01X396063Y298425D02*
G03X379528I-8268J0D01*
G01D02*
G03X396063I8267J0D01*
G01D02*
G03X379528I-8268J0D01*
G01D02*
G03X396063I8267J0D01*
G01D02*
G03X379528I-8268J0D01*
G01D02*
G03X396063I8267J0D01*
G01D02*
G03X379528I-8268J0D01*
G01D02*
G03X396063I8267J0D01*
G01X379528D02*
G03X396063I8267J0D01*
G01D02*
G03X379528I-8268J0D01*
G01D02*
G03X396063I8267J0D01*
G01D02*
G03X379528I-8268J0D01*
G01X370079Y336614D02*
Y282677D01*
G01X374016Y340551D02*
G03X370079Y336614I0J-3937D01*
G01X543307Y340551D02*
X374016D01*
G01X407087Y418110D02*
G03Y410236I0J-3937D01*
G01X381890D02*
G03Y418110I0J3937D01*
G01X396063Y437795D02*
G03X379528I-8268J0D01*
G01D02*
G03X396063I8267J0D01*
G01D02*
G03X379528I-8268J0D01*
G01D02*
G03X396063I8267J0D01*
G01D02*
G03X379528I-8268J0D01*
G01D02*
G03X396063I8267J0D01*
G01D02*
G03X379528I-8268J0D01*
G01D02*
G03X396063I8267J0D01*
G01X379528D02*
G03X396063I8267J0D01*
G01D02*
G03X379528I-8268J0D01*
G01D02*
G03X396063I8267J0D01*
G01D02*
G03X379528I-8268J0D01*
G01X374016Y418110D02*
X543307D01*
G01X370079Y422047D02*
G03X374016Y418110I3937J0D01*
G01X370079Y475984D02*
Y422047D01*
G01X396063Y368110D02*
G03X379528I-8268J0D01*
G01X396063D02*
G03X379528I-8268J0D01*
G01X396063D02*
G03X379528I-8268J0D01*
G01X396063D02*
G03X379528I-8268J0D01*
G01X396063D02*
G03X379528I-8268J0D01*
G01X396063D02*
G03X379528I-8268J0D01*
G01X374016Y410236D02*
G03X370079Y406299I0J-3937D01*
G01X543307Y410236D02*
X374016D01*
G01X407087Y487795D02*
G03Y479921I0J-3937D01*
G01X381890D02*
G03Y487795I0J3937D01*
G01X396063Y507480D02*
G03X379528I-8268J0D01*
G01D02*
G03X396063I8267J0D01*
G01D02*
G03X379528I-8268J0D01*
G01D02*
G03X396063I8267J0D01*
G01D02*
G03X379528I-8268J0D01*
G01D02*
G03X396063I8267J0D01*
G01D02*
G03X379528I-8268J0D01*
G01D02*
G03X396063I8267J0D01*
G01X379528D02*
G03X396063I8267J0D01*
G01D02*
G03X379528I-8268J0D01*
G01D02*
G03X396063I8267J0D01*
G01D02*
G03X379528I-8268J0D01*
G01X374016Y487795D02*
X543307D01*
G01X370079Y491732D02*
G03X374016Y487795I3937J0D01*
G01X370079Y545669D02*
Y491732D01*
G01X374016Y479921D02*
G03X370079Y475984I0J-3937D01*
G01X543307Y479921D02*
X374016D01*
G01X407087Y557480D02*
G03Y549606I0J-3937D01*
G01X381890D02*
G03Y557480I0J3937D01*
G01X396063Y577165D02*
G03X379528I-8268J0D01*
G01D02*
G03X396063I8267J0D01*
G01D02*
G03X379528I-8268J0D01*
G01D02*
G03X396063I8267J0D01*
G01D02*
G03X379528I-8268J0D01*
G01D02*
G03X396063I8267J0D01*
G01D02*
G03X379528I-8268J0D01*
G01D02*
G03X396063I8267J0D01*
G01X379528D02*
G03X396063I8267J0D01*
G01D02*
G03X379528I-8268J0D01*
G01D02*
G03X396063I8267J0D01*
G01D02*
G03X379528I-8268J0D01*
G01X374016Y557480D02*
X543307D01*
G01X370079Y561417D02*
G03X374016Y557480I3937J0D01*
G01X370079Y615354D02*
Y561417D01*
G01X374016Y549606D02*
G03X370079Y545669I0J-3937D01*
G01X543307Y549606D02*
X374016D01*
G01X407087Y627165D02*
G03Y619291I0J-3937D01*
G01X381890D02*
G03Y627165I0J3937D01*
G01X396063Y646850D02*
G03X379528I-8268J0D01*
G01D02*
G03X396063I8267J0D01*
G01D02*
G03X379528I-8268J0D01*
G01D02*
G03X396063I8267J0D01*
G01D02*
G03X379528I-8268J0D01*
G01D02*
G03X396063I8267J0D01*
G01D02*
G03X379528I-8268J0D01*
G01D02*
G03X396063I8267J0D01*
G01X379528D02*
G03X396063I8267J0D01*
G01D02*
G03X379528I-8268J0D01*
G01D02*
G03X396063I8267J0D01*
G01D02*
G03X379528I-8268J0D01*
G01X374016Y627165D02*
X543307D01*
G01X370079Y631102D02*
G03X374016Y627165I3937J0D01*
G01X370079Y685039D02*
Y631102D01*
G01X374016Y688976D02*
G03X370079Y685039I0J-3937D01*
G01X543307Y688976D02*
X374016D01*
G01Y619291D02*
G03X370079Y615354I0J-3937D01*
G01X543307Y619291D02*
X374016D01*
G01X510237Y-7874D02*
G03Y0I0J3937D01*
G01X537796Y19685D02*
G03X521260I-8268J0D01*
G01D02*
G03X537796I8268J0D01*
G01D02*
G03X521260I-8268J0D01*
G01D02*
G03X537796I8268J0D01*
G01D02*
G03X521260I-8268J0D01*
G01D02*
G03X537796I8268J0D01*
G01D02*
G03X521260I-8268J0D01*
G01D02*
G03X537796I8268J0D01*
G01X521260D02*
G03X537796I8268J0D01*
G01D02*
G03X521260I-8268J0D01*
G01D02*
G03X537796I8268J0D01*
G01D02*
G03X521260I-8268J0D01*
G01X510237Y61811D02*
G03Y69685I0J3937D01*
G01X537796Y89370D02*
G03X521260I-8268J0D01*
G01D02*
G03X537796I8268J0D01*
G01D02*
G03X521260I-8268J0D01*
G01D02*
G03X537796I8268J0D01*
G01D02*
G03X521260I-8268J0D01*
G01D02*
G03X537796I8268J0D01*
G01D02*
G03X521260I-8268J0D01*
G01D02*
G03X537796I8268J0D01*
G01X521260D02*
G03X537796I8268J0D01*
G01D02*
G03X521260I-8268J0D01*
G01D02*
G03X537796I8268J0D01*
G01D02*
G03X521260I-8268J0D01*
G01X510237Y131496D02*
G03Y139370I0J3937D01*
G01X537796Y159055D02*
G03X521260I-8268J0D01*
G01D02*
G03X537796I8268J0D01*
G01D02*
G03X521260I-8268J0D01*
G01D02*
G03X537796I8268J0D01*
G01D02*
G03X521260I-8268J0D01*
G01D02*
G03X537796I8268J0D01*
G01D02*
G03X521260I-8268J0D01*
G01D02*
G03X537796I8268J0D01*
G01X521260D02*
G03X537796I8268J0D01*
G01D02*
G03X521260I-8268J0D01*
G01D02*
G03X537796I8268J0D01*
G01D02*
G03X521260I-8268J0D01*
G01X510237Y270866D02*
G03Y278740I0J3937D01*
G01Y201181D02*
G03Y209055I0J3937D01*
G01X537796Y228740D02*
G03X521260I-8268J0D01*
G01D02*
G03X537796I8268J0D01*
G01D02*
G03X521260I-8268J0D01*
G01D02*
G03X537796I8268J0D01*
G01D02*
G03X521260I-8268J0D01*
G01D02*
G03X537796I8268J0D01*
G01D02*
G03X521260I-8268J0D01*
G01D02*
G03X537796I8268J0D01*
G01X521260D02*
G03X537796I8268J0D01*
G01D02*
G03X521260I-8268J0D01*
G01D02*
G03X537796I8268J0D01*
G01D02*
G03X521260I-8268J0D01*
G01X510237Y340551D02*
G03Y348425I0J3937D01*
G01X521260Y368110D02*
G03X537796I8268J0D01*
G01X521260D02*
G03X537796I8268J0D01*
G01X521260D02*
G03X537796I8268J0D01*
G01X521260D02*
G03X537796I8268J0D01*
G01X521260D02*
G03X537796I8268J0D01*
G01X521260D02*
G03X537796I8268J0D01*
G01Y298425D02*
G03X521260I-8268J0D01*
G01D02*
G03X537796I8268J0D01*
G01D02*
G03X521260I-8268J0D01*
G01D02*
G03X537796I8268J0D01*
G01D02*
G03X521260I-8268J0D01*
G01D02*
G03X537796I8268J0D01*
G01D02*
G03X521260I-8268J0D01*
G01D02*
G03X537796I8268J0D01*
G01X521260D02*
G03X537796I8268J0D01*
G01D02*
G03X521260I-8268J0D01*
G01D02*
G03X537796I8268J0D01*
G01D02*
G03X521260I-8268J0D01*
G01X510237Y410236D02*
G03Y418110I0J3937D01*
G01X537796Y437795D02*
G03X521260I-8268J0D01*
G01D02*
G03X537796I8268J0D01*
G01D02*
G03X521260I-8268J0D01*
G01D02*
G03X537796I8268J0D01*
G01D02*
G03X521260I-8268J0D01*
G01D02*
G03X537796I8268J0D01*
G01D02*
G03X521260I-8268J0D01*
G01D02*
G03X537796I8268J0D01*
G01X521260D02*
G03X537796I8268J0D01*
G01D02*
G03X521260I-8268J0D01*
G01D02*
G03X537796I8268J0D01*
G01D02*
G03X521260I-8268J0D01*
G01X537796Y368110D02*
G03X521260I-8268J0D01*
G01X537796D02*
G03X521260I-8268J0D01*
G01X537796D02*
G03X521260I-8268J0D01*
G01X537796D02*
G03X521260I-8268J0D01*
G01X537796D02*
G03X521260I-8268J0D01*
G01X537796D02*
G03X521260I-8268J0D01*
G01X510237Y479921D02*
G03Y487795I0J3937D01*
G01X537796Y507480D02*
G03X521260I-8268J0D01*
G01D02*
G03X537796I8268J0D01*
G01D02*
G03X521260I-8268J0D01*
G01D02*
G03X537796I8268J0D01*
G01D02*
G03X521260I-8268J0D01*
G01D02*
G03X537796I8268J0D01*
G01D02*
G03X521260I-8268J0D01*
G01D02*
G03X537796I8268J0D01*
G01X521260D02*
G03X537796I8268J0D01*
G01D02*
G03X521260I-8268J0D01*
G01D02*
G03X537796I8268J0D01*
G01D02*
G03X521260I-8268J0D01*
G01X510237Y549606D02*
G03Y557480I0J3937D01*
G01X537796Y577165D02*
G03X521260I-8268J0D01*
G01D02*
G03X537796I8268J0D01*
G01D02*
G03X521260I-8268J0D01*
G01D02*
G03X537796I8268J0D01*
G01D02*
G03X521260I-8268J0D01*
G01D02*
G03X537796I8268J0D01*
G01D02*
G03X521260I-8268J0D01*
G01D02*
G03X537796I8268J0D01*
G01X521260D02*
G03X537796I8268J0D01*
G01D02*
G03X521260I-8268J0D01*
G01D02*
G03X537796I8268J0D01*
G01D02*
G03X521260I-8268J0D01*
G01X510237Y619291D02*
G03Y627165I0J3937D01*
G01X537796Y646850D02*
G03X521260I-8268J0D01*
G01D02*
G03X537796I8268J0D01*
G01D02*
G03X521260I-8268J0D01*
G01D02*
G03X537796I8268J0D01*
G01D02*
G03X521260I-8268J0D01*
G01D02*
G03X537796I8268J0D01*
G01D02*
G03X521260I-8268J0D01*
G01D02*
G03X537796I8268J0D01*
G01X521260D02*
G03X537796I8268J0D01*
G01D02*
G03X521260I-8268J0D01*
G01D02*
G03X537796I8268J0D01*
G01D02*
G03X521260I-8268J0D01*
G01X539370Y-19685D02*
G03X547244Y-11811I0J7874D01*
G01X535433Y0D02*
G03Y-7874I0J-3937D01*
G01X547244D02*
Y-11811D01*
G01X535433Y-7874D02*
X547244D01*
G01Y3937D02*
Y57874D01*
G01X543307Y0D02*
G03X547244Y3937I0J3937D01*
G01X535433Y69685D02*
G03Y61811I0J-3937D01*
G01X547244Y73622D02*
Y127559D01*
G01X543307Y69685D02*
G03X547244Y73622I0J3937D01*
G01Y57874D02*
G03X543307Y61811I-3937J0D01*
G01X535433Y139370D02*
G03Y131496I0J-3937D01*
G01X547244Y143307D02*
Y197244D01*
G01X543307Y139370D02*
G03X547244Y143307I0J3937D01*
G01Y127559D02*
G03X543307Y131496I-3937J0D01*
G01X535433Y278740D02*
G03Y270866I0J-3937D01*
G01Y209055D02*
G03Y201181I0J-3937D01*
G01X543307Y278740D02*
G03X547244Y282677I0J3937D01*
G01Y212992D02*
Y266929D01*
G01X543307Y209055D02*
G03X547244Y212992I0J3937D01*
G01Y266929D02*
G03X543307Y270866I-3937J0D01*
G01X547244Y197244D02*
G03X543307Y201181I-3937J0D01*
G01X535433Y348425D02*
G03Y340551I0J-3937D01*
G01X547244Y352362D02*
Y406299D01*
G01X543307Y348425D02*
G03X547244Y352362I0J3937D01*
G01Y282677D02*
Y336614D01*
G01D02*
G03X543307Y340551I-3937J0D01*
G01X535433Y418110D02*
G03Y410236I0J-3937D01*
G01X547244Y422047D02*
Y475984D01*
G01X543307Y418110D02*
G03X547244Y422047I0J3937D01*
G01Y406299D02*
G03X543307Y410236I-3937J0D01*
G01X535433Y487795D02*
G03Y479921I0J-3937D01*
G01X547244Y491732D02*
Y545669D01*
G01X543307Y487795D02*
G03X547244Y491732I0J3937D01*
G01Y475984D02*
G03X543307Y479921I-3937J0D01*
G01X535433Y557480D02*
G03Y549606I0J-3937D01*
G01X547244Y561417D02*
Y615354D01*
G01X543307Y557480D02*
G03X547244Y561417I0J3937D01*
G01Y545669D02*
G03X543307Y549606I-3937J0D01*
G01X535433Y627165D02*
G03Y619291I0J-3937D01*
G01X547244Y631102D02*
Y685039D01*
G01X543307Y627165D02*
G03X547244Y631102I0J3937D01*
G01Y685039D02*
G03X543307Y688976I-3937J0D01*
G01X547244Y615354D02*
G03X543307Y619291I-3937J0D01*
G54D21*
X115800Y24100D03*
G54D12*
X115453Y35532D03*
X107579D03*
X99705D03*
X115453Y52264D03*
X107579D03*
X99705D03*
X123327Y35532D03*
X131201D03*
X123327Y52264D03*
X131201D03*
G54D22*
X110200Y24100D03*
G54D13*
X66900Y27500D03*
G54D14*
X70300D03*
G54D23*
X113000Y19300D03*
X63000Y39000D03*
X74000Y56200D03*
X73500Y42000D03*
X156000Y53500D03*
G54D15*
X74500Y27800D03*
X70000Y48300D03*
G54D24*
X74000Y51700D03*
G54D25*
Y48300D03*
G54D16*
X74500Y31200D03*
X70000Y51700D03*
G54D26*
X127500Y9200D03*
X131000D03*
G54D17*
X40158Y16142D03*
X105512D03*
G54D27*
X127500Y12800D03*
X131000D03*
G54D18*
X45276Y6103D03*
X49213D03*
X53150D03*
X57087D03*
X61024D03*
X64961D03*
X68898D03*
X72835D03*
X76772D03*
X80709D03*
X84646D03*
X88583D03*
X92520D03*
X96457D03*
X100394D03*
G54D19*
X85060Y31250D03*
X82500D03*
X79940D03*
Y53250D03*
X82500D03*
X85060D03*
Y46750D03*
X79940D03*
Y37750D03*
X85060D03*
G54D28*
X132000Y21000D03*
X123000D03*
G54D29*
G01X-149983Y-76117D02*
Y-156117D01*
G01D02*
X864117D01*
G01X-153983Y-60117D02*
G02I-12000J0D01*
G01X-159133D02*
G02I-6850J0D01*
G01X-165983Y-76117D02*
Y-44117D01*
G01X-149983Y-60117D02*
X-181983D01*
G01X-149983Y-76117D02*
X864117D01*
G01X-149983Y-111617D02*
X864117D01*
G01X76617Y-76117D02*
Y-156117D01*
G01X214117Y-76117D02*
Y-156117D01*
G01X329117Y-76117D02*
Y-156117D01*
G01X496617Y-76117D02*
Y-156117D01*
G01X666617Y-76117D02*
Y-156117D01*
G01X864117Y-76117D02*
Y-156117D01*
G01X892117Y-60117D02*
G02I-12000J0D01*
G01X886967D02*
G02I-6850J0D01*
G01X880117Y-76117D02*
Y-44117D01*
G01X896117Y-60117D02*
X864117D01*
M02*
